FILE_TYPE = MACRO_DRAWING;
SET COLOR_WIRE YELLOW;
SET COLOR_PROP MONO;
SET COLOR_DOT WHITE;
SET COLOR_ARC YELLOW;
SET COLOR_BODY GREEN;
SET COLOR_NOTE MONO;
SET PROP_DISPLAY VALUE;
SET PAGE_NUMBER P64;
FORCEADD TAP..1
R 2
(-5500 2125);
FORCEPROP 3 LASTPIN (-5450 2125) SIG_NAME TP_P3E_CPU1_PE1_MP_RXN<4>
J 0
(-5440 2135);
DISPLAY 0.659574 (-5440 2135);
PAINT MONO (-5440 2135);
DISPLAY INVISIBLE (-5440 2135);
FORCEPROP 1 LASTPIN (-5450 2125) BN 4
J 2
(-5438 2133);
DISPLAY 0.617021 (-5438 2133);
PAINT GREEN (-5438 2133);
FORCEPROP 2 LAST CDS_LIB mstr_standard
J 0
(-5500 2125);
PAINT MONO (-5500 2125);
DISPLAY INVISIBLE (-5500 2125);
FORCEPROP 1 LAST BODY_TYPE PLUMBING
J 2
(-5500 2175);
DISPLAY 1.446809 (-5500 2175);
PAINT GREEN (-5500 2175);
DISPLAY INVISIBLE (-5500 2175);
FORCEPROP 1 LAST HDL_TAP TRUE
J 2
(-5825 2000);
DISPLAY 1.446809 (-5825 2000);
PAINT GREEN (-5825 2000);
DISPLAY INVISIBLE (-5825 2000);
FORCEPROP 1 LAST PATH I10
J 2
(-5498 2125);
DISPLAY 0.872340 (-5498 2125);
PAINT GREEN (-5498 2125);
DISPLAY INVISIBLE (-5498 2125);
FORCEADD TAP..1
R 2
(-5500 2175);
FORCEPROP 3 LASTPIN (-5450 2175) SIG_NAME TP_P3E_CPU1_PE1_MP_RXN<5>
J 0
(-5440 2185);
DISPLAY 0.659574 (-5440 2185);
PAINT MONO (-5440 2185);
DISPLAY INVISIBLE (-5440 2185);
FORCEPROP 1 LASTPIN (-5450 2175) BN 5
J 2
(-5438 2183);
DISPLAY 0.617021 (-5438 2183);
PAINT GREEN (-5438 2183);
FORCEPROP 2 LAST CDS_LIB mstr_standard
J 0
(-5500 2175);
PAINT MONO (-5500 2175);
DISPLAY INVISIBLE (-5500 2175);
FORCEPROP 1 LAST BODY_TYPE PLUMBING
J 2
(-5500 2225);
DISPLAY 1.446809 (-5500 2225);
PAINT GREEN (-5500 2225);
DISPLAY INVISIBLE (-5500 2225);
FORCEPROP 1 LAST HDL_TAP TRUE
J 2
(-5825 2050);
DISPLAY 1.446809 (-5825 2050);
PAINT GREEN (-5825 2050);
DISPLAY INVISIBLE (-5825 2050);
FORCEPROP 1 LAST PATH I11
J 2
(-5498 2175);
DISPLAY 0.872340 (-5498 2175);
PAINT GREEN (-5498 2175);
DISPLAY INVISIBLE (-5498 2175);
FORCEADD TAP..1
R 2
(-5500 2275);
FORCEPROP 3 LASTPIN (-5450 2275) SIG_NAME TP_P3E_CPU1_PE1_MP_RXN<7>
J 0
(-5440 2285);
DISPLAY 0.659574 (-5440 2285);
PAINT MONO (-5440 2285);
DISPLAY INVISIBLE (-5440 2285);
FORCEPROP 1 LASTPIN (-5450 2275) BN 7
J 2
(-5438 2283);
DISPLAY 0.617021 (-5438 2283);
PAINT GREEN (-5438 2283);
FORCEPROP 2 LAST CDS_LIB mstr_standard
J 0
(-5500 2275);
PAINT MONO (-5500 2275);
DISPLAY INVISIBLE (-5500 2275);
FORCEPROP 1 LAST BODY_TYPE PLUMBING
J 2
(-5500 2325);
DISPLAY 1.446809 (-5500 2325);
PAINT GREEN (-5500 2325);
DISPLAY INVISIBLE (-5500 2325);
FORCEPROP 1 LAST HDL_TAP TRUE
J 2
(-5825 2150);
DISPLAY 1.446809 (-5825 2150);
PAINT GREEN (-5825 2150);
DISPLAY INVISIBLE (-5825 2150);
FORCEPROP 1 LAST PATH I12
J 2
(-5498 2275);
DISPLAY 0.872340 (-5498 2275);
PAINT GREEN (-5498 2275);
DISPLAY INVISIBLE (-5498 2275);
FORCEADD TAP..1
R 2
(-5500 2225);
FORCEPROP 3 LASTPIN (-5450 2225) SIG_NAME TP_P3E_CPU1_PE1_MP_RXN<6>
J 0
(-5440 2235);
DISPLAY 0.659574 (-5440 2235);
PAINT MONO (-5440 2235);
DISPLAY INVISIBLE (-5440 2235);
FORCEPROP 1 LASTPIN (-5450 2225) BN 6
J 2
(-5438 2233);
DISPLAY 0.617021 (-5438 2233);
PAINT GREEN (-5438 2233);
FORCEPROP 2 LAST CDS_LIB mstr_standard
J 0
(-5500 2225);
PAINT MONO (-5500 2225);
DISPLAY INVISIBLE (-5500 2225);
FORCEPROP 1 LAST BODY_TYPE PLUMBING
J 2
(-5500 2275);
DISPLAY 1.446809 (-5500 2275);
PAINT GREEN (-5500 2275);
DISPLAY INVISIBLE (-5500 2275);
FORCEPROP 1 LAST HDL_TAP TRUE
J 2
(-5825 2100);
DISPLAY 1.446809 (-5825 2100);
PAINT GREEN (-5825 2100);
DISPLAY INVISIBLE (-5825 2100);
FORCEPROP 1 LAST PATH I13
J 2
(-5498 2225);
DISPLAY 0.872340 (-5498 2225);
PAINT GREEN (-5498 2225);
DISPLAY INVISIBLE (-5498 2225);
FORCEADD TAP..1
R 2
(-5350 1975);
FORCEPROP 3 LASTPIN (-5300 1975) SIG_NAME TP_P3E_CPU1_PE1_MP_RXP<2>
J 0
(-5290 1985);
DISPLAY 0.659574 (-5290 1985);
PAINT MONO (-5290 1985);
DISPLAY INVISIBLE (-5290 1985);
FORCEPROP 1 LASTPIN (-5300 1975) BN 2
J 2
(-5288 1983);
DISPLAY 0.617021 (-5288 1983);
PAINT GREEN (-5288 1983);
FORCEPROP 2 LAST CDS_LIB mstr_standard
J 0
(-5350 1975);
PAINT MONO (-5350 1975);
DISPLAY INVISIBLE (-5350 1975);
FORCEPROP 1 LAST BODY_TYPE PLUMBING
J 2
(-5350 2025);
DISPLAY 1.446809 (-5350 2025);
PAINT GREEN (-5350 2025);
DISPLAY INVISIBLE (-5350 2025);
FORCEPROP 1 LAST HDL_TAP TRUE
J 2
(-5675 1850);
DISPLAY 1.446809 (-5675 1850);
PAINT GREEN (-5675 1850);
DISPLAY INVISIBLE (-5675 1850);
FORCEPROP 1 LAST PATH I14
J 2
(-5348 1975);
DISPLAY 0.872340 (-5348 1975);
PAINT GREEN (-5348 1975);
DISPLAY INVISIBLE (-5348 1975);
FORCEADD TAP..1
R 2
(-5350 2025);
FORCEPROP 3 LASTPIN (-5300 2025) SIG_NAME TP_P3E_CPU1_PE1_MP_RXP<3>
J 0
(-5290 2035);
DISPLAY 0.659574 (-5290 2035);
PAINT MONO (-5290 2035);
DISPLAY INVISIBLE (-5290 2035);
FORCEPROP 1 LASTPIN (-5300 2025) BN 3
J 2
(-5288 2033);
DISPLAY 0.617021 (-5288 2033);
PAINT GREEN (-5288 2033);
FORCEPROP 2 LAST CDS_LIB mstr_standard
J 0
(-5350 2025);
PAINT MONO (-5350 2025);
DISPLAY INVISIBLE (-5350 2025);
FORCEPROP 1 LAST BODY_TYPE PLUMBING
J 2
(-5350 2075);
DISPLAY 1.446809 (-5350 2075);
PAINT GREEN (-5350 2075);
DISPLAY INVISIBLE (-5350 2075);
FORCEPROP 1 LAST HDL_TAP TRUE
J 2
(-5675 1900);
DISPLAY 1.446809 (-5675 1900);
PAINT GREEN (-5675 1900);
DISPLAY INVISIBLE (-5675 1900);
FORCEPROP 1 LAST PATH I15
J 2
(-5348 2025);
DISPLAY 0.872340 (-5348 2025);
PAINT GREEN (-5348 2025);
DISPLAY INVISIBLE (-5348 2025);
FORCEADD TAP..1
R 2
(-5350 2425);
FORCEPROP 3 LASTPIN (-5300 2425) SIG_NAME TP_P3E_CPU1_PE1_MP_RXP<5>
J 0
(-5290 2435);
DISPLAY 0.659574 (-5290 2435);
PAINT MONO (-5290 2435);
DISPLAY INVISIBLE (-5290 2435);
FORCEPROP 1 LASTPIN (-5300 2425) BN 5
J 2
(-5288 2433);
DISPLAY 0.617021 (-5288 2433);
PAINT GREEN (-5288 2433);
FORCEPROP 2 LAST CDS_LIB mstr_standard
J 0
(-5350 2425);
PAINT MONO (-5350 2425);
DISPLAY INVISIBLE (-5350 2425);
FORCEPROP 1 LAST BODY_TYPE PLUMBING
J 2
(-5350 2475);
DISPLAY 1.446809 (-5350 2475);
PAINT GREEN (-5350 2475);
DISPLAY INVISIBLE (-5350 2475);
FORCEPROP 1 LAST HDL_TAP TRUE
J 2
(-5675 2300);
DISPLAY 1.446809 (-5675 2300);
PAINT GREEN (-5675 2300);
DISPLAY INVISIBLE (-5675 2300);
FORCEPROP 1 LAST PATH I16
J 2
(-5348 2425);
DISPLAY 0.872340 (-5348 2425);
PAINT GREEN (-5348 2425);
DISPLAY INVISIBLE (-5348 2425);
FORCEADD TAP..1
R 2
(-5350 2375);
FORCEPROP 3 LASTPIN (-5300 2375) SIG_NAME TP_P3E_CPU1_PE1_MP_RXP<4>
J 0
(-5290 2385);
DISPLAY 0.659574 (-5290 2385);
PAINT MONO (-5290 2385);
DISPLAY INVISIBLE (-5290 2385);
FORCEPROP 1 LASTPIN (-5300 2375) BN 4
J 2
(-5288 2383);
DISPLAY 0.617021 (-5288 2383);
PAINT GREEN (-5288 2383);
FORCEPROP 2 LAST CDS_LIB mstr_standard
J 0
(-5350 2375);
PAINT MONO (-5350 2375);
DISPLAY INVISIBLE (-5350 2375);
FORCEPROP 1 LAST BODY_TYPE PLUMBING
J 2
(-5350 2425);
DISPLAY 1.446809 (-5350 2425);
PAINT GREEN (-5350 2425);
DISPLAY INVISIBLE (-5350 2425);
FORCEPROP 1 LAST HDL_TAP TRUE
J 2
(-5675 2250);
DISPLAY 1.446809 (-5675 2250);
PAINT GREEN (-5675 2250);
DISPLAY INVISIBLE (-5675 2250);
FORCEPROP 1 LAST PATH I17
J 2
(-5348 2375);
DISPLAY 0.872340 (-5348 2375);
PAINT GREEN (-5348 2375);
DISPLAY INVISIBLE (-5348 2375);
FORCEADD TAP..1
R 2
(-5350 2475);
FORCEPROP 3 LASTPIN (-5300 2475) SIG_NAME TP_P3E_CPU1_PE1_MP_RXP<6>
J 0
(-5290 2485);
DISPLAY 0.659574 (-5290 2485);
PAINT MONO (-5290 2485);
DISPLAY INVISIBLE (-5290 2485);
FORCEPROP 1 LASTPIN (-5300 2475) BN 6
J 2
(-5288 2483);
DISPLAY 0.617021 (-5288 2483);
PAINT GREEN (-5288 2483);
FORCEPROP 2 LAST CDS_LIB mstr_standard
J 0
(-5350 2475);
PAINT MONO (-5350 2475);
DISPLAY INVISIBLE (-5350 2475);
FORCEPROP 1 LAST BODY_TYPE PLUMBING
J 2
(-5350 2525);
DISPLAY 1.446809 (-5350 2525);
PAINT GREEN (-5350 2525);
DISPLAY INVISIBLE (-5350 2525);
FORCEPROP 1 LAST HDL_TAP TRUE
J 2
(-5675 2350);
DISPLAY 1.446809 (-5675 2350);
PAINT GREEN (-5675 2350);
DISPLAY INVISIBLE (-5675 2350);
FORCEPROP 1 LAST PATH I18
J 2
(-5348 2475);
DISPLAY 0.872340 (-5348 2475);
PAINT GREEN (-5348 2475);
DISPLAY INVISIBLE (-5348 2475);
FORCEADD TAP..1
R 2
(-5500 2625);
FORCEPROP 3 LASTPIN (-5450 2625) SIG_NAME TP_P3E_CPU1_PE1_RSR3_RXN<8>
J 0
(-5440 2635);
DISPLAY 0.659574 (-5440 2635);
PAINT MONO (-5440 2635);
DISPLAY INVISIBLE (-5440 2635);
FORCEPROP 1 LASTPIN (-5450 2625) BN 8
J 2
(-5438 2633);
DISPLAY 0.617021 (-5438 2633);
PAINT GREEN (-5438 2633);
FORCEPROP 2 LAST CDS_LIB mstr_standard
J 0
(-5500 2625);
PAINT MONO (-5500 2625);
DISPLAY INVISIBLE (-5500 2625);
FORCEPROP 1 LAST BODY_TYPE PLUMBING
J 2
(-5500 2675);
DISPLAY 1.446809 (-5500 2675);
PAINT GREEN (-5500 2675);
DISPLAY INVISIBLE (-5500 2675);
FORCEPROP 1 LAST HDL_TAP TRUE
J 2
(-5825 2500);
DISPLAY 1.446809 (-5825 2500);
PAINT GREEN (-5825 2500);
DISPLAY INVISIBLE (-5825 2500);
FORCEPROP 1 LAST PATH I19
J 2
(-5498 2625);
DISPLAY 0.872340 (-5498 2625);
PAINT GREEN (-5498 2625);
DISPLAY INVISIBLE (-5498 2625);
FORCEADD TAP..1
R 2
(-5500 2675);
FORCEPROP 3 LASTPIN (-5450 2675) SIG_NAME TP_P3E_CPU1_PE1_RSR3_RXN<9>
J 0
(-5440 2685);
DISPLAY 0.659574 (-5440 2685);
PAINT MONO (-5440 2685);
DISPLAY INVISIBLE (-5440 2685);
FORCEPROP 1 LASTPIN (-5450 2675) BN 9
J 2
(-5438 2683);
DISPLAY 0.617021 (-5438 2683);
PAINT GREEN (-5438 2683);
FORCEPROP 2 LAST CDS_LIB mstr_standard
J 0
(-5500 2675);
PAINT MONO (-5500 2675);
DISPLAY INVISIBLE (-5500 2675);
FORCEPROP 1 LAST BODY_TYPE PLUMBING
J 2
(-5500 2725);
DISPLAY 1.446809 (-5500 2725);
PAINT GREEN (-5500 2725);
DISPLAY INVISIBLE (-5500 2725);
FORCEPROP 1 LAST HDL_TAP TRUE
J 2
(-5825 2550);
DISPLAY 1.446809 (-5825 2550);
PAINT GREEN (-5825 2550);
DISPLAY INVISIBLE (-5825 2550);
FORCEPROP 1 LAST PATH I20
J 2
(-5498 2675);
DISPLAY 0.872340 (-5498 2675);
PAINT GREEN (-5498 2675);
DISPLAY INVISIBLE (-5498 2675);
FORCEADD TAP..1
R 2
(-5500 2725);
FORCEPROP 3 LASTPIN (-5450 2725) SIG_NAME TP_P3E_CPU1_PE1_RSR3_RXN<10>
J 0
(-5440 2735);
DISPLAY 0.659574 (-5440 2735);
PAINT MONO (-5440 2735);
DISPLAY INVISIBLE (-5440 2735);
FORCEPROP 1 LASTPIN (-5450 2725) BN 10
J 2
(-5438 2733);
DISPLAY 0.617021 (-5438 2733);
PAINT GREEN (-5438 2733);
FORCEPROP 2 LAST CDS_LIB mstr_standard
J 0
(-5500 2725);
PAINT MONO (-5500 2725);
DISPLAY INVISIBLE (-5500 2725);
FORCEPROP 1 LAST BODY_TYPE PLUMBING
J 2
(-5500 2775);
DISPLAY 1.446809 (-5500 2775);
PAINT GREEN (-5500 2775);
DISPLAY INVISIBLE (-5500 2775);
FORCEPROP 1 LAST HDL_TAP TRUE
J 2
(-5825 2600);
DISPLAY 1.446809 (-5825 2600);
PAINT GREEN (-5825 2600);
DISPLAY INVISIBLE (-5825 2600);
FORCEPROP 1 LAST PATH I21
J 2
(-5498 2725);
DISPLAY 0.872340 (-5498 2725);
PAINT GREEN (-5498 2725);
DISPLAY INVISIBLE (-5498 2725);
FORCEADD TAP..1
R 2
(-5500 2775);
FORCEPROP 3 LASTPIN (-5450 2775) SIG_NAME TP_P3E_CPU1_PE1_RSR3_RXN<11>
J 0
(-5440 2785);
DISPLAY 0.659574 (-5440 2785);
PAINT MONO (-5440 2785);
DISPLAY INVISIBLE (-5440 2785);
FORCEPROP 1 LASTPIN (-5450 2775) BN 11
J 2
(-5438 2783);
DISPLAY 0.617021 (-5438 2783);
PAINT GREEN (-5438 2783);
FORCEPROP 2 LAST CDS_LIB mstr_standard
J 0
(-5500 2775);
PAINT MONO (-5500 2775);
DISPLAY INVISIBLE (-5500 2775);
FORCEPROP 1 LAST BODY_TYPE PLUMBING
J 2
(-5500 2825);
DISPLAY 1.446809 (-5500 2825);
PAINT GREEN (-5500 2825);
DISPLAY INVISIBLE (-5500 2825);
FORCEPROP 1 LAST HDL_TAP TRUE
J 2
(-5825 2650);
DISPLAY 1.446809 (-5825 2650);
PAINT GREEN (-5825 2650);
DISPLAY INVISIBLE (-5825 2650);
FORCEPROP 1 LAST PATH I22
J 2
(-5498 2775);
DISPLAY 0.872340 (-5498 2775);
PAINT GREEN (-5498 2775);
DISPLAY INVISIBLE (-5498 2775);
FORCEADD TAP..1
R 2
(-5350 2525);
FORCEPROP 3 LASTPIN (-5300 2525) SIG_NAME TP_P3E_CPU1_PE1_MP_RXP<7>
J 0
(-5290 2535);
DISPLAY 0.659574 (-5290 2535);
PAINT MONO (-5290 2535);
DISPLAY INVISIBLE (-5290 2535);
FORCEPROP 1 LASTPIN (-5300 2525) BN 7
J 2
(-5288 2533);
DISPLAY 0.617021 (-5288 2533);
PAINT GREEN (-5288 2533);
FORCEPROP 2 LAST CDS_LIB mstr_standard
J 0
(-5350 2525);
PAINT MONO (-5350 2525);
DISPLAY INVISIBLE (-5350 2525);
FORCEPROP 1 LAST BODY_TYPE PLUMBING
J 2
(-5350 2575);
DISPLAY 1.446809 (-5350 2575);
PAINT GREEN (-5350 2575);
DISPLAY INVISIBLE (-5350 2575);
FORCEPROP 1 LAST HDL_TAP TRUE
J 2
(-5675 2400);
DISPLAY 1.446809 (-5675 2400);
PAINT GREEN (-5675 2400);
DISPLAY INVISIBLE (-5675 2400);
FORCEPROP 1 LAST PATH I23
J 2
(-5348 2525);
DISPLAY 0.872340 (-5348 2525);
PAINT GREEN (-5348 2525);
DISPLAY INVISIBLE (-5348 2525);
FORCEADD TAP..1
R 2
(-5350 2875);
FORCEPROP 3 LASTPIN (-5300 2875) SIG_NAME TP_P3E_CPU1_PE1_RSR3_RXP<8>
J 0
(-5290 2885);
DISPLAY 0.659574 (-5290 2885);
PAINT MONO (-5290 2885);
DISPLAY INVISIBLE (-5290 2885);
FORCEPROP 1 LASTPIN (-5300 2875) BN 8
J 2
(-5288 2883);
DISPLAY 0.617021 (-5288 2883);
PAINT GREEN (-5288 2883);
FORCEPROP 2 LAST CDS_LIB mstr_standard
J 0
(-5350 2875);
PAINT MONO (-5350 2875);
DISPLAY INVISIBLE (-5350 2875);
FORCEPROP 1 LAST BODY_TYPE PLUMBING
J 2
(-5350 2925);
DISPLAY 1.446809 (-5350 2925);
PAINT GREEN (-5350 2925);
DISPLAY INVISIBLE (-5350 2925);
FORCEPROP 1 LAST HDL_TAP TRUE
J 2
(-5675 2750);
DISPLAY 1.446809 (-5675 2750);
PAINT GREEN (-5675 2750);
DISPLAY INVISIBLE (-5675 2750);
FORCEPROP 1 LAST PATH I24
J 2
(-5348 2875);
DISPLAY 0.872340 (-5348 2875);
PAINT GREEN (-5348 2875);
DISPLAY INVISIBLE (-5348 2875);
FORCEADD TAP..1
R 2
(-5350 2925);
FORCEPROP 3 LASTPIN (-5300 2925) SIG_NAME TP_P3E_CPU1_PE1_RSR3_RXP<9>
J 0
(-5290 2935);
DISPLAY 0.659574 (-5290 2935);
PAINT MONO (-5290 2935);
DISPLAY INVISIBLE (-5290 2935);
FORCEPROP 1 LASTPIN (-5300 2925) BN 9
J 2
(-5288 2933);
DISPLAY 0.617021 (-5288 2933);
PAINT GREEN (-5288 2933);
FORCEPROP 2 LAST CDS_LIB mstr_standard
J 0
(-5350 2925);
PAINT MONO (-5350 2925);
DISPLAY INVISIBLE (-5350 2925);
FORCEPROP 1 LAST BODY_TYPE PLUMBING
J 2
(-5350 2975);
DISPLAY 1.446809 (-5350 2975);
PAINT GREEN (-5350 2975);
DISPLAY INVISIBLE (-5350 2975);
FORCEPROP 1 LAST HDL_TAP TRUE
J 2
(-5675 2800);
DISPLAY 1.446809 (-5675 2800);
PAINT GREEN (-5675 2800);
DISPLAY INVISIBLE (-5675 2800);
FORCEPROP 1 LAST PATH I25
J 2
(-5348 2925);
DISPLAY 0.872340 (-5348 2925);
PAINT GREEN (-5348 2925);
DISPLAY INVISIBLE (-5348 2925);
FORCEADD TAP..1
R 2
(-5350 2975);
FORCEPROP 3 LASTPIN (-5300 2975) SIG_NAME TP_P3E_CPU1_PE1_RSR3_RXP<10>
J 0
(-5290 2985);
DISPLAY 0.659574 (-5290 2985);
PAINT MONO (-5290 2985);
DISPLAY INVISIBLE (-5290 2985);
FORCEPROP 1 LASTPIN (-5300 2975) BN 10
J 2
(-5288 2983);
DISPLAY 0.617021 (-5288 2983);
PAINT GREEN (-5288 2983);
FORCEPROP 2 LAST CDS_LIB mstr_standard
J 0
(-5350 2975);
PAINT MONO (-5350 2975);
DISPLAY INVISIBLE (-5350 2975);
FORCEPROP 1 LAST BODY_TYPE PLUMBING
J 2
(-5350 3025);
DISPLAY 1.446809 (-5350 3025);
PAINT GREEN (-5350 3025);
DISPLAY INVISIBLE (-5350 3025);
FORCEPROP 1 LAST HDL_TAP TRUE
J 2
(-5675 2850);
DISPLAY 1.446809 (-5675 2850);
PAINT GREEN (-5675 2850);
DISPLAY INVISIBLE (-5675 2850);
FORCEPROP 1 LAST PATH I26
J 2
(-5348 2975);
DISPLAY 0.872340 (-5348 2975);
PAINT GREEN (-5348 2975);
DISPLAY INVISIBLE (-5348 2975);
FORCEADD TAP..1
R 2
(-5500 3225);
FORCEPROP 3 LASTPIN (-5450 3225) SIG_NAME TP_P3E_CPU1_PE1_RSR3_RXN<14>
J 0
(-5440 3235);
DISPLAY 0.659574 (-5440 3235);
PAINT MONO (-5440 3235);
DISPLAY INVISIBLE (-5440 3235);
FORCEPROP 1 LASTPIN (-5450 3225) BN 14
J 2
(-5438 3233);
DISPLAY 0.617021 (-5438 3233);
PAINT GREEN (-5438 3233);
FORCEPROP 2 LAST CDS_LIB mstr_standard
J 0
(-5500 3225);
PAINT MONO (-5500 3225);
DISPLAY INVISIBLE (-5500 3225);
FORCEPROP 1 LAST BODY_TYPE PLUMBING
J 2
(-5500 3275);
DISPLAY 1.446809 (-5500 3275);
PAINT GREEN (-5500 3275);
DISPLAY INVISIBLE (-5500 3275);
FORCEPROP 1 LAST HDL_TAP TRUE
J 2
(-5825 3100);
DISPLAY 1.446809 (-5825 3100);
PAINT GREEN (-5825 3100);
DISPLAY INVISIBLE (-5825 3100);
FORCEPROP 1 LAST PATH I27
J 2
(-5498 3225);
DISPLAY 0.872340 (-5498 3225);
PAINT GREEN (-5498 3225);
DISPLAY INVISIBLE (-5498 3225);
FORCEADD TAP..1
R 2
(-5500 3175);
FORCEPROP 3 LASTPIN (-5450 3175) SIG_NAME TP_P3E_CPU1_PE1_RSR3_RXN<13>
J 0
(-5440 3185);
DISPLAY 0.659574 (-5440 3185);
PAINT MONO (-5440 3185);
DISPLAY INVISIBLE (-5440 3185);
FORCEPROP 1 LASTPIN (-5450 3175) BN 13
J 2
(-5438 3183);
DISPLAY 0.617021 (-5438 3183);
PAINT GREEN (-5438 3183);
FORCEPROP 2 LAST CDS_LIB mstr_standard
J 0
(-5500 3175);
PAINT MONO (-5500 3175);
DISPLAY INVISIBLE (-5500 3175);
FORCEPROP 1 LAST BODY_TYPE PLUMBING
J 2
(-5500 3225);
DISPLAY 1.446809 (-5500 3225);
PAINT GREEN (-5500 3225);
DISPLAY INVISIBLE (-5500 3225);
FORCEPROP 1 LAST HDL_TAP TRUE
J 2
(-5825 3050);
DISPLAY 1.446809 (-5825 3050);
PAINT GREEN (-5825 3050);
DISPLAY INVISIBLE (-5825 3050);
FORCEPROP 1 LAST PATH I28
J 2
(-5498 3175);
DISPLAY 0.872340 (-5498 3175);
PAINT GREEN (-5498 3175);
DISPLAY INVISIBLE (-5498 3175);
FORCEADD TAP..1
R 2
(-5500 3125);
FORCEPROP 3 LASTPIN (-5450 3125) SIG_NAME TP_P3E_CPU1_PE1_RSR3_RXN<12>
J 0
(-5440 3135);
DISPLAY 0.659574 (-5440 3135);
PAINT MONO (-5440 3135);
DISPLAY INVISIBLE (-5440 3135);
FORCEPROP 1 LASTPIN (-5450 3125) BN 12
J 2
(-5438 3133);
DISPLAY 0.617021 (-5438 3133);
PAINT GREEN (-5438 3133);
FORCEPROP 2 LAST CDS_LIB mstr_standard
J 0
(-5500 3125);
PAINT MONO (-5500 3125);
DISPLAY INVISIBLE (-5500 3125);
FORCEPROP 1 LAST BODY_TYPE PLUMBING
J 2
(-5500 3175);
DISPLAY 1.446809 (-5500 3175);
PAINT GREEN (-5500 3175);
DISPLAY INVISIBLE (-5500 3175);
FORCEPROP 1 LAST HDL_TAP TRUE
J 2
(-5825 3000);
DISPLAY 1.446809 (-5825 3000);
PAINT GREEN (-5825 3000);
DISPLAY INVISIBLE (-5825 3000);
FORCEPROP 1 LAST PATH I29
J 2
(-5498 3125);
DISPLAY 0.872340 (-5498 3125);
PAINT GREEN (-5498 3125);
DISPLAY INVISIBLE (-5498 3125);
FORCEADD TAP..1
R 2
(-5500 1625);
FORCEPROP 3 LASTPIN (-5450 1625) SIG_NAME TP_P3E_CPU1_PE1_MP_RXN<0>
J 0
(-5440 1635);
DISPLAY 0.659574 (-5440 1635);
PAINT MONO (-5440 1635);
DISPLAY INVISIBLE (-5440 1635);
FORCEPROP 1 LASTPIN (-5450 1625) BN 0
J 2
(-5438 1633);
DISPLAY 0.617021 (-5438 1633);
PAINT GREEN (-5438 1633);
FORCEPROP 2 LAST CDS_LIB mstr_standard
J 0
(-5500 1625);
PAINT MONO (-5500 1625);
DISPLAY INVISIBLE (-5500 1625);
FORCEPROP 1 LAST BODY_TYPE PLUMBING
J 2
(-5500 1675);
DISPLAY 1.446809 (-5500 1675);
PAINT GREEN (-5500 1675);
DISPLAY INVISIBLE (-5500 1675);
FORCEPROP 1 LAST HDL_TAP TRUE
J 2
(-5825 1500);
DISPLAY 1.446809 (-5825 1500);
PAINT GREEN (-5825 1500);
DISPLAY INVISIBLE (-5825 1500);
FORCEPROP 1 LAST PATH I3
J 2
(-5498 1625);
DISPLAY 0.872340 (-5498 1625);
PAINT GREEN (-5498 1625);
DISPLAY INVISIBLE (-5498 1625);
FORCEADD TAP..1
R 2
(-5500 3275);
FORCEPROP 3 LASTPIN (-5450 3275) SIG_NAME TP_P3E_CPU1_PE1_RSR3_RXN<15>
J 0
(-5440 3285);
DISPLAY 0.659574 (-5440 3285);
PAINT MONO (-5440 3285);
DISPLAY INVISIBLE (-5440 3285);
FORCEPROP 1 LASTPIN (-5450 3275) BN 15
J 2
(-5438 3283);
DISPLAY 0.617021 (-5438 3283);
PAINT GREEN (-5438 3283);
FORCEPROP 2 LAST CDS_LIB mstr_standard
J 0
(-5500 3275);
PAINT MONO (-5500 3275);
DISPLAY INVISIBLE (-5500 3275);
FORCEPROP 1 LAST BODY_TYPE PLUMBING
J 2
(-5500 3325);
DISPLAY 1.446809 (-5500 3325);
PAINT GREEN (-5500 3325);
DISPLAY INVISIBLE (-5500 3325);
FORCEPROP 1 LAST HDL_TAP TRUE
J 2
(-5825 3150);
DISPLAY 1.446809 (-5825 3150);
PAINT GREEN (-5825 3150);
DISPLAY INVISIBLE (-5825 3150);
FORCEPROP 1 LAST PATH I30
J 2
(-5498 3275);
DISPLAY 0.872340 (-5498 3275);
PAINT GREEN (-5498 3275);
DISPLAY INVISIBLE (-5498 3275);
FORCEADD TAP..1
R 2
(-5350 3025);
FORCEPROP 3 LASTPIN (-5300 3025) SIG_NAME TP_P3E_CPU1_PE1_RSR3_RXP<11>
J 0
(-5290 3035);
DISPLAY 0.659574 (-5290 3035);
PAINT MONO (-5290 3035);
DISPLAY INVISIBLE (-5290 3035);
FORCEPROP 1 LASTPIN (-5300 3025) BN 11
J 2
(-5288 3033);
DISPLAY 0.617021 (-5288 3033);
PAINT GREEN (-5288 3033);
FORCEPROP 2 LAST CDS_LIB mstr_standard
J 0
(-5350 3025);
PAINT MONO (-5350 3025);
DISPLAY INVISIBLE (-5350 3025);
FORCEPROP 1 LAST BODY_TYPE PLUMBING
J 2
(-5350 3075);
DISPLAY 1.446809 (-5350 3075);
PAINT GREEN (-5350 3075);
DISPLAY INVISIBLE (-5350 3075);
FORCEPROP 1 LAST HDL_TAP TRUE
J 2
(-5675 2900);
DISPLAY 1.446809 (-5675 2900);
PAINT GREEN (-5675 2900);
DISPLAY INVISIBLE (-5675 2900);
FORCEPROP 1 LAST PATH I31
J 2
(-5348 3025);
DISPLAY 0.872340 (-5348 3025);
PAINT GREEN (-5348 3025);
DISPLAY INVISIBLE (-5348 3025);
FORCEADD TAP..1
R 2
(-5350 3375);
FORCEPROP 3 LASTPIN (-5300 3375) SIG_NAME TP_P3E_CPU1_PE1_RSR3_RXP<12>
J 0
(-5290 3385);
DISPLAY 0.659574 (-5290 3385);
PAINT MONO (-5290 3385);
DISPLAY INVISIBLE (-5290 3385);
FORCEPROP 1 LASTPIN (-5300 3375) BN 12
J 2
(-5288 3383);
DISPLAY 0.617021 (-5288 3383);
PAINT GREEN (-5288 3383);
FORCEPROP 2 LAST CDS_LIB mstr_standard
J 0
(-5350 3375);
PAINT MONO (-5350 3375);
DISPLAY INVISIBLE (-5350 3375);
FORCEPROP 1 LAST BODY_TYPE PLUMBING
J 2
(-5350 3425);
DISPLAY 1.446809 (-5350 3425);
PAINT GREEN (-5350 3425);
DISPLAY INVISIBLE (-5350 3425);
FORCEPROP 1 LAST HDL_TAP TRUE
J 2
(-5675 3250);
DISPLAY 1.446809 (-5675 3250);
PAINT GREEN (-5675 3250);
DISPLAY INVISIBLE (-5675 3250);
FORCEPROP 1 LAST PATH I32
J 2
(-5348 3375);
DISPLAY 0.872340 (-5348 3375);
PAINT GREEN (-5348 3375);
DISPLAY INVISIBLE (-5348 3375);
FORCEADD TAP..1
R 2
(-5350 3425);
FORCEPROP 3 LASTPIN (-5300 3425) SIG_NAME TP_P3E_CPU1_PE1_RSR3_RXP<13>
J 0
(-5290 3435);
DISPLAY 0.659574 (-5290 3435);
PAINT MONO (-5290 3435);
DISPLAY INVISIBLE (-5290 3435);
FORCEPROP 1 LASTPIN (-5300 3425) BN 13
J 2
(-5288 3433);
DISPLAY 0.617021 (-5288 3433);
PAINT GREEN (-5288 3433);
FORCEPROP 2 LAST CDS_LIB mstr_standard
J 0
(-5350 3425);
PAINT MONO (-5350 3425);
DISPLAY INVISIBLE (-5350 3425);
FORCEPROP 1 LAST BODY_TYPE PLUMBING
J 2
(-5350 3475);
DISPLAY 1.446809 (-5350 3475);
PAINT GREEN (-5350 3475);
DISPLAY INVISIBLE (-5350 3475);
FORCEPROP 1 LAST HDL_TAP TRUE
J 2
(-5675 3300);
DISPLAY 1.446809 (-5675 3300);
PAINT GREEN (-5675 3300);
DISPLAY INVISIBLE (-5675 3300);
FORCEPROP 1 LAST PATH I33
J 2
(-5348 3425);
DISPLAY 0.872340 (-5348 3425);
PAINT GREEN (-5348 3425);
DISPLAY INVISIBLE (-5348 3425);
FORCEADD TAP..1
R 2
(-5350 3475);
FORCEPROP 3 LASTPIN (-5300 3475) SIG_NAME TP_P3E_CPU1_PE1_RSR3_RXP<14>
J 0
(-5290 3485);
DISPLAY 0.659574 (-5290 3485);
PAINT MONO (-5290 3485);
DISPLAY INVISIBLE (-5290 3485);
FORCEPROP 1 LASTPIN (-5300 3475) BN 14
J 2
(-5288 3483);
DISPLAY 0.617021 (-5288 3483);
PAINT GREEN (-5288 3483);
FORCEPROP 2 LAST CDS_LIB mstr_standard
J 0
(-5350 3475);
PAINT MONO (-5350 3475);
DISPLAY INVISIBLE (-5350 3475);
FORCEPROP 1 LAST BODY_TYPE PLUMBING
J 2
(-5350 3525);
DISPLAY 1.446809 (-5350 3525);
PAINT GREEN (-5350 3525);
DISPLAY INVISIBLE (-5350 3525);
FORCEPROP 1 LAST HDL_TAP TRUE
J 2
(-5675 3350);
DISPLAY 1.446809 (-5675 3350);
PAINT GREEN (-5675 3350);
DISPLAY INVISIBLE (-5675 3350);
FORCEPROP 1 LAST PATH I34
J 2
(-5348 3475);
DISPLAY 0.872340 (-5348 3475);
PAINT GREEN (-5348 3475);
DISPLAY INVISIBLE (-5348 3475);
FORCEADD TAP..1
R 2
(-5350 3525);
FORCEPROP 3 LASTPIN (-5300 3525) SIG_NAME TP_P3E_CPU1_PE1_RSR3_RXP<15>
J 0
(-5290 3535);
DISPLAY 0.659574 (-5290 3535);
PAINT MONO (-5290 3535);
DISPLAY INVISIBLE (-5290 3535);
FORCEPROP 1 LASTPIN (-5300 3525) BN 15
J 2
(-5288 3533);
DISPLAY 0.617021 (-5288 3533);
PAINT GREEN (-5288 3533);
FORCEPROP 2 LAST CDS_LIB mstr_standard
J 0
(-5350 3525);
PAINT MONO (-5350 3525);
DISPLAY INVISIBLE (-5350 3525);
FORCEPROP 1 LAST BODY_TYPE PLUMBING
J 2
(-5350 3575);
DISPLAY 1.446809 (-5350 3575);
PAINT GREEN (-5350 3575);
DISPLAY INVISIBLE (-5350 3575);
FORCEPROP 1 LAST HDL_TAP TRUE
J 2
(-5675 3400);
DISPLAY 1.446809 (-5675 3400);
PAINT GREEN (-5675 3400);
DISPLAY INVISIBLE (-5675 3400);
FORCEPROP 1 LAST PATH I35
J 2
(-5348 3525);
DISPLAY 0.872340 (-5348 3525);
PAINT GREEN (-5348 3525);
DISPLAY INVISIBLE (-5348 3525);
FORCEADD TAP..1
(-2725 1625);
FORCEPROP 3 LASTPIN (-2775 1625) SIG_NAME TP_P3E_CPU1_PE1_MP_TXN<0>
J 0
(-2765 1635);
DISPLAY 0.659574 (-2765 1635);
PAINT MONO (-2765 1635);
DISPLAY INVISIBLE (-2765 1635);
FORCEPROP 1 LASTPIN (-2775 1625) BN 0
J 0
(-2787 1633);
DISPLAY 0.617021 (-2787 1633);
PAINT GREEN (-2787 1633);
FORCEPROP 2 LAST CDS_LIB mstr_standard
J 2
(-2725 1625);
PAINT MONO (-2725 1625);
DISPLAY INVISIBLE (-2725 1625);
FORCEPROP 1 LAST BODY_TYPE PLUMBING
J 0
(-2725 1675);
DISPLAY 1.446809 (-2725 1675);
PAINT GREEN (-2725 1675);
DISPLAY INVISIBLE (-2725 1675);
FORCEPROP 1 LAST HDL_TAP TRUE
J 0
(-2400 1500);
DISPLAY 1.446809 (-2400 1500);
PAINT GREEN (-2400 1500);
DISPLAY INVISIBLE (-2400 1500);
FORCEPROP 1 LAST PATH I36
J 0
(-2727 1625);
DISPLAY 0.872340 (-2727 1625);
PAINT GREEN (-2727 1625);
DISPLAY INVISIBLE (-2727 1625);
FORCEADD TAP..1
(-2725 1675);
FORCEPROP 3 LASTPIN (-2775 1675) SIG_NAME TP_P3E_CPU1_PE1_MP_TXN<1>
J 0
(-2765 1685);
DISPLAY 0.659574 (-2765 1685);
PAINT MONO (-2765 1685);
DISPLAY INVISIBLE (-2765 1685);
FORCEPROP 1 LASTPIN (-2775 1675) BN 1
J 0
(-2787 1683);
DISPLAY 0.617021 (-2787 1683);
PAINT GREEN (-2787 1683);
FORCEPROP 2 LAST CDS_LIB mstr_standard
J 2
(-2725 1675);
PAINT MONO (-2725 1675);
DISPLAY INVISIBLE (-2725 1675);
FORCEPROP 1 LAST BODY_TYPE PLUMBING
J 0
(-2725 1725);
DISPLAY 1.446809 (-2725 1725);
PAINT GREEN (-2725 1725);
DISPLAY INVISIBLE (-2725 1725);
FORCEPROP 1 LAST HDL_TAP TRUE
J 0
(-2400 1550);
DISPLAY 1.446809 (-2400 1550);
PAINT GREEN (-2400 1550);
DISPLAY INVISIBLE (-2400 1550);
FORCEPROP 1 LAST PATH I37
J 0
(-2727 1675);
DISPLAY 0.872340 (-2727 1675);
PAINT GREEN (-2727 1675);
DISPLAY INVISIBLE (-2727 1675);
FORCEADD TAP..1
(-2875 1925);
FORCEPROP 3 LASTPIN (-2925 1925) SIG_NAME TP_P3E_CPU1_PE1_MP_TXP<1>
J 0
(-2915 1935);
DISPLAY 0.659574 (-2915 1935);
PAINT MONO (-2915 1935);
DISPLAY INVISIBLE (-2915 1935);
FORCEPROP 1 LASTPIN (-2925 1925) BN 1
J 0
(-2937 1933);
DISPLAY 0.617021 (-2937 1933);
PAINT GREEN (-2937 1933);
FORCEPROP 2 LAST CDS_LIB mstr_standard
J 2
(-2875 1925);
PAINT MONO (-2875 1925);
DISPLAY INVISIBLE (-2875 1925);
FORCEPROP 1 LAST BODY_TYPE PLUMBING
J 0
(-2875 1975);
DISPLAY 1.446809 (-2875 1975);
PAINT GREEN (-2875 1975);
DISPLAY INVISIBLE (-2875 1975);
FORCEPROP 1 LAST HDL_TAP TRUE
J 0
(-2550 1800);
DISPLAY 1.446809 (-2550 1800);
PAINT GREEN (-2550 1800);
DISPLAY INVISIBLE (-2550 1800);
FORCEPROP 1 LAST PATH I38
J 0
(-2877 1925);
DISPLAY 0.872340 (-2877 1925);
PAINT GREEN (-2877 1925);
DISPLAY INVISIBLE (-2877 1925);
FORCEADD TAP..1
(-2875 1875);
FORCEPROP 3 LASTPIN (-2925 1875) SIG_NAME TP_P3E_CPU1_PE1_MP_TXP<0>
J 0
(-2915 1885);
DISPLAY 0.659574 (-2915 1885);
PAINT MONO (-2915 1885);
DISPLAY INVISIBLE (-2915 1885);
FORCEPROP 1 LASTPIN (-2925 1875) BN 0
J 0
(-2937 1883);
DISPLAY 0.617021 (-2937 1883);
PAINT GREEN (-2937 1883);
FORCEPROP 2 LAST CDS_LIB mstr_standard
J 2
(-2875 1875);
PAINT MONO (-2875 1875);
DISPLAY INVISIBLE (-2875 1875);
FORCEPROP 1 LAST BODY_TYPE PLUMBING
J 0
(-2875 1925);
DISPLAY 1.446809 (-2875 1925);
PAINT GREEN (-2875 1925);
DISPLAY INVISIBLE (-2875 1925);
FORCEPROP 1 LAST HDL_TAP TRUE
J 0
(-2550 1750);
DISPLAY 1.446809 (-2550 1750);
PAINT GREEN (-2550 1750);
DISPLAY INVISIBLE (-2550 1750);
FORCEPROP 1 LAST PATH I39
J 0
(-2877 1875);
DISPLAY 0.872340 (-2877 1875);
PAINT GREEN (-2877 1875);
DISPLAY INVISIBLE (-2877 1875);
FORCEADD TAP..1
R 2
(-5500 1675);
FORCEPROP 3 LASTPIN (-5450 1675) SIG_NAME TP_P3E_CPU1_PE1_MP_RXN<1>
J 0
(-5440 1685);
DISPLAY 0.659574 (-5440 1685);
PAINT MONO (-5440 1685);
DISPLAY INVISIBLE (-5440 1685);
FORCEPROP 1 LASTPIN (-5450 1675) BN 1
J 2
(-5438 1683);
DISPLAY 0.617021 (-5438 1683);
PAINT GREEN (-5438 1683);
FORCEPROP 2 LAST CDS_LIB mstr_standard
J 0
(-5500 1675);
PAINT MONO (-5500 1675);
DISPLAY INVISIBLE (-5500 1675);
FORCEPROP 1 LAST BODY_TYPE PLUMBING
J 2
(-5500 1725);
DISPLAY 1.446809 (-5500 1725);
PAINT GREEN (-5500 1725);
DISPLAY INVISIBLE (-5500 1725);
FORCEPROP 1 LAST HDL_TAP TRUE
J 2
(-5825 1550);
DISPLAY 1.446809 (-5825 1550);
PAINT GREEN (-5825 1550);
DISPLAY INVISIBLE (-5825 1550);
FORCEPROP 1 LAST PATH I4
J 2
(-5498 1675);
DISPLAY 0.872340 (-5498 1675);
PAINT GREEN (-5498 1675);
DISPLAY INVISIBLE (-5498 1675);
FORCEADD TAP..1
(-2725 1775);
FORCEPROP 3 LASTPIN (-2775 1775) SIG_NAME TP_P3E_CPU1_PE1_MP_TXN<3>
J 0
(-2765 1785);
DISPLAY 0.659574 (-2765 1785);
PAINT MONO (-2765 1785);
DISPLAY INVISIBLE (-2765 1785);
FORCEPROP 1 LASTPIN (-2775 1775) BN 3
J 0
(-2787 1783);
DISPLAY 0.617021 (-2787 1783);
PAINT GREEN (-2787 1783);
FORCEPROP 2 LAST CDS_LIB mstr_standard
J 2
(-2725 1775);
PAINT MONO (-2725 1775);
DISPLAY INVISIBLE (-2725 1775);
FORCEPROP 1 LAST BODY_TYPE PLUMBING
J 0
(-2725 1825);
DISPLAY 1.446809 (-2725 1825);
PAINT GREEN (-2725 1825);
DISPLAY INVISIBLE (-2725 1825);
FORCEPROP 1 LAST HDL_TAP TRUE
J 0
(-2400 1650);
DISPLAY 1.446809 (-2400 1650);
PAINT GREEN (-2400 1650);
DISPLAY INVISIBLE (-2400 1650);
FORCEPROP 1 LAST PATH I40
J 0
(-2727 1775);
DISPLAY 0.872340 (-2727 1775);
PAINT GREEN (-2727 1775);
DISPLAY INVISIBLE (-2727 1775);
FORCEADD TAP..1
(-2725 1725);
FORCEPROP 3 LASTPIN (-2775 1725) SIG_NAME TP_P3E_CPU1_PE1_MP_TXN<2>
J 0
(-2765 1735);
DISPLAY 0.659574 (-2765 1735);
PAINT MONO (-2765 1735);
DISPLAY INVISIBLE (-2765 1735);
FORCEPROP 1 LASTPIN (-2775 1725) BN 2
J 0
(-2787 1733);
DISPLAY 0.617021 (-2787 1733);
PAINT GREEN (-2787 1733);
FORCEPROP 2 LAST CDS_LIB mstr_standard
J 2
(-2725 1725);
PAINT MONO (-2725 1725);
DISPLAY INVISIBLE (-2725 1725);
FORCEPROP 1 LAST BODY_TYPE PLUMBING
J 0
(-2725 1775);
DISPLAY 1.446809 (-2725 1775);
PAINT GREEN (-2725 1775);
DISPLAY INVISIBLE (-2725 1775);
FORCEPROP 1 LAST HDL_TAP TRUE
J 0
(-2400 1600);
DISPLAY 1.446809 (-2400 1600);
PAINT GREEN (-2400 1600);
DISPLAY INVISIBLE (-2400 1600);
FORCEPROP 1 LAST PATH I41
J 0
(-2727 1725);
DISPLAY 0.872340 (-2727 1725);
PAINT GREEN (-2727 1725);
DISPLAY INVISIBLE (-2727 1725);
FORCEADD TAP..1
(-2875 2025);
FORCEPROP 3 LASTPIN (-2925 2025) SIG_NAME TP_P3E_CPU1_PE1_MP_TXP<3>
J 0
(-2915 2035);
DISPLAY 0.659574 (-2915 2035);
PAINT MONO (-2915 2035);
DISPLAY INVISIBLE (-2915 2035);
FORCEPROP 1 LASTPIN (-2925 2025) BN 3
J 0
(-2937 2033);
DISPLAY 0.617021 (-2937 2033);
PAINT GREEN (-2937 2033);
FORCEPROP 2 LAST CDS_LIB mstr_standard
J 2
(-2875 2025);
PAINT MONO (-2875 2025);
DISPLAY INVISIBLE (-2875 2025);
FORCEPROP 1 LAST BODY_TYPE PLUMBING
J 0
(-2875 2075);
DISPLAY 1.446809 (-2875 2075);
PAINT GREEN (-2875 2075);
DISPLAY INVISIBLE (-2875 2075);
FORCEPROP 1 LAST HDL_TAP TRUE
J 0
(-2550 1900);
DISPLAY 1.446809 (-2550 1900);
PAINT GREEN (-2550 1900);
DISPLAY INVISIBLE (-2550 1900);
FORCEPROP 1 LAST PATH I42
J 0
(-2877 2025);
DISPLAY 0.872340 (-2877 2025);
PAINT GREEN (-2877 2025);
DISPLAY INVISIBLE (-2877 2025);
FORCEADD TAP..1
(-2875 1975);
FORCEPROP 3 LASTPIN (-2925 1975) SIG_NAME TP_P3E_CPU1_PE1_MP_TXP<2>
J 0
(-2915 1985);
DISPLAY 0.659574 (-2915 1985);
PAINT MONO (-2915 1985);
DISPLAY INVISIBLE (-2915 1985);
FORCEPROP 1 LASTPIN (-2925 1975) BN 2
J 0
(-2937 1983);
DISPLAY 0.617021 (-2937 1983);
PAINT GREEN (-2937 1983);
FORCEPROP 2 LAST CDS_LIB mstr_standard
J 2
(-2875 1975);
PAINT MONO (-2875 1975);
DISPLAY INVISIBLE (-2875 1975);
FORCEPROP 1 LAST BODY_TYPE PLUMBING
J 0
(-2875 2025);
DISPLAY 1.446809 (-2875 2025);
PAINT GREEN (-2875 2025);
DISPLAY INVISIBLE (-2875 2025);
FORCEPROP 1 LAST HDL_TAP TRUE
J 0
(-2550 1850);
DISPLAY 1.446809 (-2550 1850);
PAINT GREEN (-2550 1850);
DISPLAY INVISIBLE (-2550 1850);
FORCEPROP 1 LAST PATH I43
J 0
(-2877 1975);
DISPLAY 0.872340 (-2877 1975);
PAINT GREEN (-2877 1975);
DISPLAY INVISIBLE (-2877 1975);
FORCEADD TAP..1
(-2725 2125);
FORCEPROP 3 LASTPIN (-2775 2125) SIG_NAME TP_P3E_CPU1_PE1_MP_TXN<4>
J 0
(-2765 2135);
DISPLAY 0.659574 (-2765 2135);
PAINT MONO (-2765 2135);
DISPLAY INVISIBLE (-2765 2135);
FORCEPROP 1 LASTPIN (-2775 2125) BN 4
J 0
(-2787 2133);
DISPLAY 0.617021 (-2787 2133);
PAINT GREEN (-2787 2133);
FORCEPROP 2 LAST CDS_LIB mstr_standard
J 2
(-2725 2125);
PAINT MONO (-2725 2125);
DISPLAY INVISIBLE (-2725 2125);
FORCEPROP 1 LAST BODY_TYPE PLUMBING
J 0
(-2725 2175);
DISPLAY 1.446809 (-2725 2175);
PAINT GREEN (-2725 2175);
DISPLAY INVISIBLE (-2725 2175);
FORCEPROP 1 LAST HDL_TAP TRUE
J 0
(-2400 2000);
DISPLAY 1.446809 (-2400 2000);
PAINT GREEN (-2400 2000);
DISPLAY INVISIBLE (-2400 2000);
FORCEPROP 1 LAST PATH I44
J 0
(-2727 2125);
DISPLAY 0.872340 (-2727 2125);
PAINT GREEN (-2727 2125);
DISPLAY INVISIBLE (-2727 2125);
FORCEADD TAP..1
(-2725 2175);
FORCEPROP 3 LASTPIN (-2775 2175) SIG_NAME TP_P3E_CPU1_PE1_MP_TXN<5>
J 0
(-2765 2185);
DISPLAY 0.659574 (-2765 2185);
PAINT MONO (-2765 2185);
DISPLAY INVISIBLE (-2765 2185);
FORCEPROP 1 LASTPIN (-2775 2175) BN 5
J 0
(-2787 2183);
DISPLAY 0.617021 (-2787 2183);
PAINT GREEN (-2787 2183);
FORCEPROP 2 LAST CDS_LIB mstr_standard
J 2
(-2725 2175);
PAINT MONO (-2725 2175);
DISPLAY INVISIBLE (-2725 2175);
FORCEPROP 1 LAST BODY_TYPE PLUMBING
J 0
(-2725 2225);
DISPLAY 1.446809 (-2725 2225);
PAINT GREEN (-2725 2225);
DISPLAY INVISIBLE (-2725 2225);
FORCEPROP 1 LAST HDL_TAP TRUE
J 0
(-2400 2050);
DISPLAY 1.446809 (-2400 2050);
PAINT GREEN (-2400 2050);
DISPLAY INVISIBLE (-2400 2050);
FORCEPROP 1 LAST PATH I45
J 0
(-2727 2175);
DISPLAY 0.872340 (-2727 2175);
PAINT GREEN (-2727 2175);
DISPLAY INVISIBLE (-2727 2175);
FORCEADD TAP..1
(-2725 2225);
FORCEPROP 3 LASTPIN (-2775 2225) SIG_NAME TP_P3E_CPU1_PE1_MP_TXN<6>
J 0
(-2765 2235);
DISPLAY 0.659574 (-2765 2235);
PAINT MONO (-2765 2235);
DISPLAY INVISIBLE (-2765 2235);
FORCEPROP 1 LASTPIN (-2775 2225) BN 6
J 0
(-2787 2233);
DISPLAY 0.617021 (-2787 2233);
PAINT GREEN (-2787 2233);
FORCEPROP 2 LAST CDS_LIB mstr_standard
J 2
(-2725 2225);
PAINT MONO (-2725 2225);
DISPLAY INVISIBLE (-2725 2225);
FORCEPROP 1 LAST BODY_TYPE PLUMBING
J 0
(-2725 2275);
DISPLAY 1.446809 (-2725 2275);
PAINT GREEN (-2725 2275);
DISPLAY INVISIBLE (-2725 2275);
FORCEPROP 1 LAST HDL_TAP TRUE
J 0
(-2400 2100);
DISPLAY 1.446809 (-2400 2100);
PAINT GREEN (-2400 2100);
DISPLAY INVISIBLE (-2400 2100);
FORCEPROP 1 LAST PATH I46
J 0
(-2727 2225);
DISPLAY 0.872340 (-2727 2225);
PAINT GREEN (-2727 2225);
DISPLAY INVISIBLE (-2727 2225);
FORCEADD TAP..1
(-2875 2375);
FORCEPROP 3 LASTPIN (-2925 2375) SIG_NAME TP_P3E_CPU1_PE1_MP_TXP<4>
J 0
(-2915 2385);
DISPLAY 0.659574 (-2915 2385);
PAINT MONO (-2915 2385);
DISPLAY INVISIBLE (-2915 2385);
FORCEPROP 1 LASTPIN (-2925 2375) BN 4
J 0
(-2937 2383);
DISPLAY 0.617021 (-2937 2383);
PAINT GREEN (-2937 2383);
FORCEPROP 2 LAST CDS_LIB mstr_standard
J 2
(-2875 2375);
PAINT MONO (-2875 2375);
DISPLAY INVISIBLE (-2875 2375);
FORCEPROP 1 LAST BODY_TYPE PLUMBING
J 0
(-2875 2425);
DISPLAY 1.446809 (-2875 2425);
PAINT GREEN (-2875 2425);
DISPLAY INVISIBLE (-2875 2425);
FORCEPROP 1 LAST HDL_TAP TRUE
J 0
(-2550 2250);
DISPLAY 1.446809 (-2550 2250);
PAINT GREEN (-2550 2250);
DISPLAY INVISIBLE (-2550 2250);
FORCEPROP 1 LAST PATH I47
J 0
(-2877 2375);
DISPLAY 0.872340 (-2877 2375);
PAINT GREEN (-2877 2375);
DISPLAY INVISIBLE (-2877 2375);
FORCEADD TAP..1
(-2875 2425);
FORCEPROP 3 LASTPIN (-2925 2425) SIG_NAME TP_P3E_CPU1_PE1_MP_TXP<5>
J 0
(-2915 2435);
DISPLAY 0.659574 (-2915 2435);
PAINT MONO (-2915 2435);
DISPLAY INVISIBLE (-2915 2435);
FORCEPROP 1 LASTPIN (-2925 2425) BN 5
J 0
(-2937 2433);
DISPLAY 0.617021 (-2937 2433);
PAINT GREEN (-2937 2433);
FORCEPROP 2 LAST CDS_LIB mstr_standard
J 2
(-2875 2425);
PAINT MONO (-2875 2425);
DISPLAY INVISIBLE (-2875 2425);
FORCEPROP 1 LAST BODY_TYPE PLUMBING
J 0
(-2875 2475);
DISPLAY 1.446809 (-2875 2475);
PAINT GREEN (-2875 2475);
DISPLAY INVISIBLE (-2875 2475);
FORCEPROP 1 LAST HDL_TAP TRUE
J 0
(-2550 2300);
DISPLAY 1.446809 (-2550 2300);
PAINT GREEN (-2550 2300);
DISPLAY INVISIBLE (-2550 2300);
FORCEPROP 1 LAST PATH I48
J 0
(-2877 2425);
DISPLAY 0.872340 (-2877 2425);
PAINT GREEN (-2877 2425);
DISPLAY INVISIBLE (-2877 2425);
FORCEADD TAP..1
(-2875 2475);
FORCEPROP 3 LASTPIN (-2925 2475) SIG_NAME TP_P3E_CPU1_PE1_MP_TXP<6>
J 0
(-2915 2485);
DISPLAY 0.659574 (-2915 2485);
PAINT MONO (-2915 2485);
DISPLAY INVISIBLE (-2915 2485);
FORCEPROP 1 LASTPIN (-2925 2475) BN 6
J 0
(-2937 2483);
DISPLAY 0.617021 (-2937 2483);
PAINT GREEN (-2937 2483);
FORCEPROP 2 LAST CDS_LIB mstr_standard
J 2
(-2875 2475);
PAINT MONO (-2875 2475);
DISPLAY INVISIBLE (-2875 2475);
FORCEPROP 1 LAST BODY_TYPE PLUMBING
J 0
(-2875 2525);
DISPLAY 1.446809 (-2875 2525);
PAINT GREEN (-2875 2525);
DISPLAY INVISIBLE (-2875 2525);
FORCEPROP 1 LAST HDL_TAP TRUE
J 0
(-2550 2350);
DISPLAY 1.446809 (-2550 2350);
PAINT GREEN (-2550 2350);
DISPLAY INVISIBLE (-2550 2350);
FORCEPROP 1 LAST PATH I49
J 0
(-2877 2475);
DISPLAY 0.872340 (-2877 2475);
PAINT GREEN (-2877 2475);
DISPLAY INVISIBLE (-2877 2475);
FORCEADD TAP..1
R 2
(-5500 1725);
FORCEPROP 3 LASTPIN (-5450 1725) SIG_NAME TP_P3E_CPU1_PE1_MP_RXN<2>
J 0
(-5440 1735);
DISPLAY 0.659574 (-5440 1735);
PAINT MONO (-5440 1735);
DISPLAY INVISIBLE (-5440 1735);
FORCEPROP 1 LASTPIN (-5450 1725) BN 2
J 2
(-5438 1733);
DISPLAY 0.617021 (-5438 1733);
PAINT GREEN (-5438 1733);
FORCEPROP 2 LAST CDS_LIB mstr_standard
J 0
(-5500 1725);
PAINT MONO (-5500 1725);
DISPLAY INVISIBLE (-5500 1725);
FORCEPROP 1 LAST BODY_TYPE PLUMBING
J 2
(-5500 1775);
DISPLAY 1.446809 (-5500 1775);
PAINT GREEN (-5500 1775);
DISPLAY INVISIBLE (-5500 1775);
FORCEPROP 1 LAST HDL_TAP TRUE
J 2
(-5825 1600);
DISPLAY 1.446809 (-5825 1600);
PAINT GREEN (-5825 1600);
DISPLAY INVISIBLE (-5825 1600);
FORCEPROP 1 LAST PATH I5
J 2
(-5498 1725);
DISPLAY 0.872340 (-5498 1725);
PAINT GREEN (-5498 1725);
DISPLAY INVISIBLE (-5498 1725);
FORCEADD TAP..1
(-2725 2275);
FORCEPROP 3 LASTPIN (-2775 2275) SIG_NAME TP_P3E_CPU1_PE1_MP_TXN<7>
J 0
(-2765 2285);
DISPLAY 0.659574 (-2765 2285);
PAINT MONO (-2765 2285);
DISPLAY INVISIBLE (-2765 2285);
FORCEPROP 1 LASTPIN (-2775 2275) BN 7
J 0
(-2787 2283);
DISPLAY 0.617021 (-2787 2283);
PAINT GREEN (-2787 2283);
FORCEPROP 2 LAST CDS_LIB mstr_standard
J 2
(-2725 2275);
PAINT MONO (-2725 2275);
DISPLAY INVISIBLE (-2725 2275);
FORCEPROP 1 LAST BODY_TYPE PLUMBING
J 0
(-2725 2325);
DISPLAY 1.446809 (-2725 2325);
PAINT GREEN (-2725 2325);
DISPLAY INVISIBLE (-2725 2325);
FORCEPROP 1 LAST HDL_TAP TRUE
J 0
(-2400 2150);
DISPLAY 1.446809 (-2400 2150);
PAINT GREEN (-2400 2150);
DISPLAY INVISIBLE (-2400 2150);
FORCEPROP 1 LAST PATH I50
J 0
(-2727 2275);
DISPLAY 0.872340 (-2727 2275);
PAINT GREEN (-2727 2275);
DISPLAY INVISIBLE (-2727 2275);
FORCEADD TAP..1
(-2875 2525);
FORCEPROP 3 LASTPIN (-2925 2525) SIG_NAME TP_P3E_CPU1_PE1_MP_TXP<7>
J 0
(-2915 2535);
DISPLAY 0.659574 (-2915 2535);
PAINT MONO (-2915 2535);
DISPLAY INVISIBLE (-2915 2535);
FORCEPROP 1 LASTPIN (-2925 2525) BN 7
J 0
(-2937 2533);
DISPLAY 0.617021 (-2937 2533);
PAINT GREEN (-2937 2533);
FORCEPROP 2 LAST CDS_LIB mstr_standard
J 2
(-2875 2525);
PAINT MONO (-2875 2525);
DISPLAY INVISIBLE (-2875 2525);
FORCEPROP 1 LAST BODY_TYPE PLUMBING
J 0
(-2875 2575);
DISPLAY 1.446809 (-2875 2575);
PAINT GREEN (-2875 2575);
DISPLAY INVISIBLE (-2875 2575);
FORCEPROP 1 LAST HDL_TAP TRUE
J 0
(-2550 2400);
DISPLAY 1.446809 (-2550 2400);
PAINT GREEN (-2550 2400);
DISPLAY INVISIBLE (-2550 2400);
FORCEPROP 1 LAST PATH I51
J 0
(-2877 2525);
DISPLAY 0.872340 (-2877 2525);
PAINT GREEN (-2877 2525);
DISPLAY INVISIBLE (-2877 2525);
FORCEADD TAP..1
(-2725 2625);
FORCEPROP 3 LASTPIN (-2775 2625) SIG_NAME TP_P3E_CPU1_PE1_RSR3_TXN<8>
J 0
(-2765 2635);
DISPLAY 0.659574 (-2765 2635);
PAINT MONO (-2765 2635);
DISPLAY INVISIBLE (-2765 2635);
FORCEPROP 1 LASTPIN (-2775 2625) BN 8
J 0
(-2787 2633);
DISPLAY 0.617021 (-2787 2633);
PAINT GREEN (-2787 2633);
FORCEPROP 2 LAST CDS_LIB mstr_standard
J 2
(-2725 2625);
PAINT MONO (-2725 2625);
DISPLAY INVISIBLE (-2725 2625);
FORCEPROP 1 LAST BODY_TYPE PLUMBING
J 0
(-2725 2675);
DISPLAY 1.446809 (-2725 2675);
PAINT GREEN (-2725 2675);
DISPLAY INVISIBLE (-2725 2675);
FORCEPROP 1 LAST HDL_TAP TRUE
J 0
(-2400 2500);
DISPLAY 1.446809 (-2400 2500);
PAINT GREEN (-2400 2500);
DISPLAY INVISIBLE (-2400 2500);
FORCEPROP 1 LAST PATH I52
J 0
(-2727 2625);
DISPLAY 0.872340 (-2727 2625);
PAINT GREEN (-2727 2625);
DISPLAY INVISIBLE (-2727 2625);
FORCEADD TAP..1
(-2725 2725);
FORCEPROP 3 LASTPIN (-2775 2725) SIG_NAME TP_P3E_CPU1_PE1_RSR3_TXN<10>
J 0
(-2765 2735);
DISPLAY 0.659574 (-2765 2735);
PAINT MONO (-2765 2735);
DISPLAY INVISIBLE (-2765 2735);
FORCEPROP 1 LASTPIN (-2775 2725) BN 10
J 0
(-2787 2733);
DISPLAY 0.617021 (-2787 2733);
PAINT GREEN (-2787 2733);
FORCEPROP 2 LAST CDS_LIB mstr_standard
J 2
(-2725 2725);
PAINT MONO (-2725 2725);
DISPLAY INVISIBLE (-2725 2725);
FORCEPROP 1 LAST BODY_TYPE PLUMBING
J 0
(-2725 2775);
DISPLAY 1.446809 (-2725 2775);
PAINT GREEN (-2725 2775);
DISPLAY INVISIBLE (-2725 2775);
FORCEPROP 1 LAST HDL_TAP TRUE
J 0
(-2400 2600);
DISPLAY 1.446809 (-2400 2600);
PAINT GREEN (-2400 2600);
DISPLAY INVISIBLE (-2400 2600);
FORCEPROP 1 LAST PATH I53
J 0
(-2727 2725);
DISPLAY 0.872340 (-2727 2725);
PAINT GREEN (-2727 2725);
DISPLAY INVISIBLE (-2727 2725);
FORCEADD TAP..1
(-2725 2675);
FORCEPROP 3 LASTPIN (-2775 2675) SIG_NAME TP_P3E_CPU1_PE1_RSR3_TXN<9>
J 0
(-2765 2685);
DISPLAY 0.659574 (-2765 2685);
PAINT MONO (-2765 2685);
DISPLAY INVISIBLE (-2765 2685);
FORCEPROP 1 LASTPIN (-2775 2675) BN 9
J 0
(-2787 2683);
DISPLAY 0.617021 (-2787 2683);
PAINT GREEN (-2787 2683);
FORCEPROP 2 LAST CDS_LIB mstr_standard
J 2
(-2725 2675);
PAINT MONO (-2725 2675);
DISPLAY INVISIBLE (-2725 2675);
FORCEPROP 1 LAST BODY_TYPE PLUMBING
J 0
(-2725 2725);
DISPLAY 1.446809 (-2725 2725);
PAINT GREEN (-2725 2725);
DISPLAY INVISIBLE (-2725 2725);
FORCEPROP 1 LAST HDL_TAP TRUE
J 0
(-2400 2550);
DISPLAY 1.446809 (-2400 2550);
PAINT GREEN (-2400 2550);
DISPLAY INVISIBLE (-2400 2550);
FORCEPROP 1 LAST PATH I54
J 0
(-2727 2675);
DISPLAY 0.872340 (-2727 2675);
PAINT GREEN (-2727 2675);
DISPLAY INVISIBLE (-2727 2675);
FORCEADD TAP..1
(-2875 2875);
FORCEPROP 3 LASTPIN (-2925 2875) SIG_NAME TP_P3E_CPU1_PE1_RSR3_TXP<8>
J 0
(-2915 2885);
DISPLAY 0.659574 (-2915 2885);
PAINT MONO (-2915 2885);
DISPLAY INVISIBLE (-2915 2885);
FORCEPROP 1 LASTPIN (-2925 2875) BN 8
J 0
(-2937 2883);
DISPLAY 0.617021 (-2937 2883);
PAINT GREEN (-2937 2883);
FORCEPROP 2 LAST CDS_LIB mstr_standard
J 2
(-2875 2875);
PAINT MONO (-2875 2875);
DISPLAY INVISIBLE (-2875 2875);
FORCEPROP 1 LAST BODY_TYPE PLUMBING
J 0
(-2875 2925);
DISPLAY 1.446809 (-2875 2925);
PAINT GREEN (-2875 2925);
DISPLAY INVISIBLE (-2875 2925);
FORCEPROP 1 LAST HDL_TAP TRUE
J 0
(-2550 2750);
DISPLAY 1.446809 (-2550 2750);
PAINT GREEN (-2550 2750);
DISPLAY INVISIBLE (-2550 2750);
FORCEPROP 1 LAST PATH I55
J 0
(-2877 2875);
DISPLAY 0.872340 (-2877 2875);
PAINT GREEN (-2877 2875);
DISPLAY INVISIBLE (-2877 2875);
FORCEADD TAP..1
(-2875 2925);
FORCEPROP 3 LASTPIN (-2925 2925) SIG_NAME TP_P3E_CPU1_PE1_RSR3_TXP<9>
J 0
(-2915 2935);
DISPLAY 0.659574 (-2915 2935);
PAINT MONO (-2915 2935);
DISPLAY INVISIBLE (-2915 2935);
FORCEPROP 1 LASTPIN (-2925 2925) BN 9
J 0
(-2937 2933);
DISPLAY 0.617021 (-2937 2933);
PAINT GREEN (-2937 2933);
FORCEPROP 2 LAST CDS_LIB mstr_standard
J 2
(-2875 2925);
PAINT MONO (-2875 2925);
DISPLAY INVISIBLE (-2875 2925);
FORCEPROP 1 LAST BODY_TYPE PLUMBING
J 0
(-2875 2975);
DISPLAY 1.446809 (-2875 2975);
PAINT GREEN (-2875 2975);
DISPLAY INVISIBLE (-2875 2975);
FORCEPROP 1 LAST HDL_TAP TRUE
J 0
(-2550 2800);
DISPLAY 1.446809 (-2550 2800);
PAINT GREEN (-2550 2800);
DISPLAY INVISIBLE (-2550 2800);
FORCEPROP 1 LAST PATH I56
J 0
(-2877 2925);
DISPLAY 0.872340 (-2877 2925);
PAINT GREEN (-2877 2925);
DISPLAY INVISIBLE (-2877 2925);
FORCEADD TAP..1
(-2875 2975);
FORCEPROP 3 LASTPIN (-2925 2975) SIG_NAME TP_P3E_CPU1_PE1_RSR3_TXP<10>
J 0
(-2915 2985);
DISPLAY 0.659574 (-2915 2985);
PAINT MONO (-2915 2985);
DISPLAY INVISIBLE (-2915 2985);
FORCEPROP 1 LASTPIN (-2925 2975) BN 10
J 0
(-2937 2983);
DISPLAY 0.617021 (-2937 2983);
PAINT GREEN (-2937 2983);
FORCEPROP 2 LAST CDS_LIB mstr_standard
J 2
(-2875 2975);
PAINT MONO (-2875 2975);
DISPLAY INVISIBLE (-2875 2975);
FORCEPROP 1 LAST BODY_TYPE PLUMBING
J 0
(-2875 3025);
DISPLAY 1.446809 (-2875 3025);
PAINT GREEN (-2875 3025);
DISPLAY INVISIBLE (-2875 3025);
FORCEPROP 1 LAST HDL_TAP TRUE
J 0
(-2550 2850);
DISPLAY 1.446809 (-2550 2850);
PAINT GREEN (-2550 2850);
DISPLAY INVISIBLE (-2550 2850);
FORCEPROP 1 LAST PATH I57
J 0
(-2877 2975);
DISPLAY 0.872340 (-2877 2975);
PAINT GREEN (-2877 2975);
DISPLAY INVISIBLE (-2877 2975);
FORCEADD TAP..1
(-2725 2775);
FORCEPROP 3 LASTPIN (-2775 2775) SIG_NAME TP_P3E_CPU1_PE1_RSR3_TXN<11>
J 0
(-2765 2785);
DISPLAY 0.659574 (-2765 2785);
PAINT MONO (-2765 2785);
DISPLAY INVISIBLE (-2765 2785);
FORCEPROP 1 LASTPIN (-2775 2775) BN 11
J 0
(-2787 2783);
DISPLAY 0.617021 (-2787 2783);
PAINT GREEN (-2787 2783);
FORCEPROP 2 LAST CDS_LIB mstr_standard
J 2
(-2725 2775);
PAINT MONO (-2725 2775);
DISPLAY INVISIBLE (-2725 2775);
FORCEPROP 1 LAST BODY_TYPE PLUMBING
J 0
(-2725 2825);
DISPLAY 1.446809 (-2725 2825);
PAINT GREEN (-2725 2825);
DISPLAY INVISIBLE (-2725 2825);
FORCEPROP 1 LAST HDL_TAP TRUE
J 0
(-2400 2650);
DISPLAY 1.446809 (-2400 2650);
PAINT GREEN (-2400 2650);
DISPLAY INVISIBLE (-2400 2650);
FORCEPROP 1 LAST PATH I58
J 0
(-2727 2775);
DISPLAY 0.872340 (-2727 2775);
PAINT GREEN (-2727 2775);
DISPLAY INVISIBLE (-2727 2775);
FORCEADD TAP..1
(-2875 3025);
FORCEPROP 3 LASTPIN (-2925 3025) SIG_NAME TP_P3E_CPU1_PE1_RSR3_TXP<11>
J 0
(-2915 3035);
DISPLAY 0.659574 (-2915 3035);
PAINT MONO (-2915 3035);
DISPLAY INVISIBLE (-2915 3035);
FORCEPROP 1 LASTPIN (-2925 3025) BN 11
J 0
(-2937 3033);
DISPLAY 0.617021 (-2937 3033);
PAINT GREEN (-2937 3033);
FORCEPROP 2 LAST CDS_LIB mstr_standard
J 2
(-2875 3025);
PAINT MONO (-2875 3025);
DISPLAY INVISIBLE (-2875 3025);
FORCEPROP 1 LAST BODY_TYPE PLUMBING
J 0
(-2875 3075);
DISPLAY 1.446809 (-2875 3075);
PAINT GREEN (-2875 3075);
DISPLAY INVISIBLE (-2875 3075);
FORCEPROP 1 LAST HDL_TAP TRUE
J 0
(-2550 2900);
DISPLAY 1.446809 (-2550 2900);
PAINT GREEN (-2550 2900);
DISPLAY INVISIBLE (-2550 2900);
FORCEPROP 1 LAST PATH I59
J 0
(-2877 3025);
DISPLAY 0.872340 (-2877 3025);
PAINT GREEN (-2877 3025);
DISPLAY INVISIBLE (-2877 3025);
FORCEADD TAP..1
R 2
(-5500 1775);
FORCEPROP 3 LASTPIN (-5450 1775) SIG_NAME TP_P3E_CPU1_PE1_MP_RXN<3>
J 0
(-5440 1785);
DISPLAY 0.659574 (-5440 1785);
PAINT MONO (-5440 1785);
DISPLAY INVISIBLE (-5440 1785);
FORCEPROP 1 LASTPIN (-5450 1775) BN 3
J 2
(-5438 1783);
DISPLAY 0.617021 (-5438 1783);
PAINT GREEN (-5438 1783);
FORCEPROP 2 LAST CDS_LIB mstr_standard
J 0
(-5500 1775);
PAINT MONO (-5500 1775);
DISPLAY INVISIBLE (-5500 1775);
FORCEPROP 1 LAST BODY_TYPE PLUMBING
J 2
(-5500 1825);
DISPLAY 1.446809 (-5500 1825);
PAINT GREEN (-5500 1825);
DISPLAY INVISIBLE (-5500 1825);
FORCEPROP 1 LAST HDL_TAP TRUE
J 2
(-5825 1650);
DISPLAY 1.446809 (-5825 1650);
PAINT GREEN (-5825 1650);
DISPLAY INVISIBLE (-5825 1650);
FORCEPROP 1 LAST PATH I6
J 2
(-5498 1775);
DISPLAY 0.872340 (-5498 1775);
PAINT GREEN (-5498 1775);
DISPLAY INVISIBLE (-5498 1775);
FORCEADD TAP..1
(-2725 3125);
FORCEPROP 3 LASTPIN (-2775 3125) SIG_NAME TP_P3E_CPU1_PE1_RSR3_TXN<12>
J 0
(-2765 3135);
DISPLAY 0.659574 (-2765 3135);
PAINT MONO (-2765 3135);
DISPLAY INVISIBLE (-2765 3135);
FORCEPROP 1 LASTPIN (-2775 3125) BN 12
J 0
(-2787 3133);
DISPLAY 0.617021 (-2787 3133);
PAINT GREEN (-2787 3133);
FORCEPROP 2 LAST CDS_LIB mstr_standard
J 2
(-2725 3125);
PAINT MONO (-2725 3125);
DISPLAY INVISIBLE (-2725 3125);
FORCEPROP 1 LAST BODY_TYPE PLUMBING
J 0
(-2725 3175);
DISPLAY 1.446809 (-2725 3175);
PAINT GREEN (-2725 3175);
DISPLAY INVISIBLE (-2725 3175);
FORCEPROP 1 LAST HDL_TAP TRUE
J 0
(-2400 3000);
DISPLAY 1.446809 (-2400 3000);
PAINT GREEN (-2400 3000);
DISPLAY INVISIBLE (-2400 3000);
FORCEPROP 1 LAST PATH I60
J 0
(-2727 3125);
DISPLAY 0.872340 (-2727 3125);
PAINT GREEN (-2727 3125);
DISPLAY INVISIBLE (-2727 3125);
FORCEADD TAP..1
(-2725 3175);
FORCEPROP 3 LASTPIN (-2775 3175) SIG_NAME TP_P3E_CPU1_PE1_RSR3_TXN<13>
J 0
(-2765 3185);
DISPLAY 0.659574 (-2765 3185);
PAINT MONO (-2765 3185);
DISPLAY INVISIBLE (-2765 3185);
FORCEPROP 1 LASTPIN (-2775 3175) BN 13
J 0
(-2787 3183);
DISPLAY 0.617021 (-2787 3183);
PAINT GREEN (-2787 3183);
FORCEPROP 2 LAST CDS_LIB mstr_standard
J 2
(-2725 3175);
PAINT MONO (-2725 3175);
DISPLAY INVISIBLE (-2725 3175);
FORCEPROP 1 LAST BODY_TYPE PLUMBING
J 0
(-2725 3225);
DISPLAY 1.446809 (-2725 3225);
PAINT GREEN (-2725 3225);
DISPLAY INVISIBLE (-2725 3225);
FORCEPROP 1 LAST HDL_TAP TRUE
J 0
(-2400 3050);
DISPLAY 1.446809 (-2400 3050);
PAINT GREEN (-2400 3050);
DISPLAY INVISIBLE (-2400 3050);
FORCEPROP 1 LAST PATH I61
J 0
(-2727 3175);
DISPLAY 0.872340 (-2727 3175);
PAINT GREEN (-2727 3175);
DISPLAY INVISIBLE (-2727 3175);
FORCEADD TAP..1
(-2725 3225);
FORCEPROP 3 LASTPIN (-2775 3225) SIG_NAME TP_P3E_CPU1_PE1_RSR3_TXN<14>
J 0
(-2765 3235);
DISPLAY 0.659574 (-2765 3235);
PAINT MONO (-2765 3235);
DISPLAY INVISIBLE (-2765 3235);
FORCEPROP 1 LASTPIN (-2775 3225) BN 14
J 0
(-2787 3233);
DISPLAY 0.617021 (-2787 3233);
PAINT GREEN (-2787 3233);
FORCEPROP 2 LAST CDS_LIB mstr_standard
J 2
(-2725 3225);
PAINT MONO (-2725 3225);
DISPLAY INVISIBLE (-2725 3225);
FORCEPROP 1 LAST BODY_TYPE PLUMBING
J 0
(-2725 3275);
DISPLAY 1.446809 (-2725 3275);
PAINT GREEN (-2725 3275);
DISPLAY INVISIBLE (-2725 3275);
FORCEPROP 1 LAST HDL_TAP TRUE
J 0
(-2400 3100);
DISPLAY 1.446809 (-2400 3100);
PAINT GREEN (-2400 3100);
DISPLAY INVISIBLE (-2400 3100);
FORCEPROP 1 LAST PATH I62
J 0
(-2727 3225);
DISPLAY 0.872340 (-2727 3225);
PAINT GREEN (-2727 3225);
DISPLAY INVISIBLE (-2727 3225);
FORCEADD TAP..1
(-2875 3375);
FORCEPROP 3 LASTPIN (-2925 3375) SIG_NAME TP_P3E_CPU1_PE1_RSR3_TXP<12>
J 0
(-2915 3385);
DISPLAY 0.659574 (-2915 3385);
PAINT MONO (-2915 3385);
DISPLAY INVISIBLE (-2915 3385);
FORCEPROP 1 LASTPIN (-2925 3375) BN 12
J 0
(-2937 3383);
DISPLAY 0.617021 (-2937 3383);
PAINT GREEN (-2937 3383);
FORCEPROP 2 LAST CDS_LIB mstr_standard
J 2
(-2875 3375);
PAINT MONO (-2875 3375);
DISPLAY INVISIBLE (-2875 3375);
FORCEPROP 1 LAST BODY_TYPE PLUMBING
J 0
(-2875 3425);
DISPLAY 1.446809 (-2875 3425);
PAINT GREEN (-2875 3425);
DISPLAY INVISIBLE (-2875 3425);
FORCEPROP 1 LAST HDL_TAP TRUE
J 0
(-2550 3250);
DISPLAY 1.446809 (-2550 3250);
PAINT GREEN (-2550 3250);
DISPLAY INVISIBLE (-2550 3250);
FORCEPROP 1 LAST PATH I63
J 0
(-2877 3375);
DISPLAY 0.872340 (-2877 3375);
PAINT GREEN (-2877 3375);
DISPLAY INVISIBLE (-2877 3375);
FORCEADD TAP..1
(-2875 3425);
FORCEPROP 3 LASTPIN (-2925 3425) SIG_NAME TP_P3E_CPU1_PE1_RSR3_TXP<13>
J 0
(-2915 3435);
DISPLAY 0.659574 (-2915 3435);
PAINT MONO (-2915 3435);
DISPLAY INVISIBLE (-2915 3435);
FORCEPROP 1 LASTPIN (-2925 3425) BN 13
J 0
(-2937 3433);
DISPLAY 0.617021 (-2937 3433);
PAINT GREEN (-2937 3433);
FORCEPROP 2 LAST CDS_LIB mstr_standard
J 2
(-2875 3425);
PAINT MONO (-2875 3425);
DISPLAY INVISIBLE (-2875 3425);
FORCEPROP 1 LAST BODY_TYPE PLUMBING
J 0
(-2875 3475);
DISPLAY 1.446809 (-2875 3475);
PAINT GREEN (-2875 3475);
DISPLAY INVISIBLE (-2875 3475);
FORCEPROP 1 LAST HDL_TAP TRUE
J 0
(-2550 3300);
DISPLAY 1.446809 (-2550 3300);
PAINT GREEN (-2550 3300);
DISPLAY INVISIBLE (-2550 3300);
FORCEPROP 1 LAST PATH I64
J 0
(-2877 3425);
DISPLAY 0.872340 (-2877 3425);
PAINT GREEN (-2877 3425);
DISPLAY INVISIBLE (-2877 3425);
FORCEADD TAP..1
(-2875 3475);
FORCEPROP 3 LASTPIN (-2925 3475) SIG_NAME TP_P3E_CPU1_PE1_RSR3_TXP<14>
J 0
(-2915 3485);
DISPLAY 0.659574 (-2915 3485);
PAINT MONO (-2915 3485);
DISPLAY INVISIBLE (-2915 3485);
FORCEPROP 1 LASTPIN (-2925 3475) BN 14
J 0
(-2937 3483);
DISPLAY 0.617021 (-2937 3483);
PAINT GREEN (-2937 3483);
FORCEPROP 2 LAST CDS_LIB mstr_standard
J 2
(-2875 3475);
PAINT MONO (-2875 3475);
DISPLAY INVISIBLE (-2875 3475);
FORCEPROP 1 LAST BODY_TYPE PLUMBING
J 0
(-2875 3525);
DISPLAY 1.446809 (-2875 3525);
PAINT GREEN (-2875 3525);
DISPLAY INVISIBLE (-2875 3525);
FORCEPROP 1 LAST HDL_TAP TRUE
J 0
(-2550 3350);
DISPLAY 1.446809 (-2550 3350);
PAINT GREEN (-2550 3350);
DISPLAY INVISIBLE (-2550 3350);
FORCEPROP 1 LAST PATH I65
J 0
(-2877 3475);
DISPLAY 0.872340 (-2877 3475);
PAINT GREEN (-2877 3475);
DISPLAY INVISIBLE (-2877 3475);
FORCEADD TAP..1
(-2725 3275);
FORCEPROP 3 LASTPIN (-2775 3275) SIG_NAME TP_P3E_CPU1_PE1_RSR3_TXN<15>
J 0
(-2765 3285);
DISPLAY 0.659574 (-2765 3285);
PAINT MONO (-2765 3285);
DISPLAY INVISIBLE (-2765 3285);
FORCEPROP 1 LASTPIN (-2775 3275) BN 15
J 0
(-2787 3283);
DISPLAY 0.617021 (-2787 3283);
PAINT GREEN (-2787 3283);
FORCEPROP 2 LAST CDS_LIB mstr_standard
J 2
(-2725 3275);
PAINT MONO (-2725 3275);
DISPLAY INVISIBLE (-2725 3275);
FORCEPROP 1 LAST BODY_TYPE PLUMBING
J 0
(-2725 3325);
DISPLAY 1.446809 (-2725 3325);
PAINT GREEN (-2725 3325);
DISPLAY INVISIBLE (-2725 3325);
FORCEPROP 1 LAST HDL_TAP TRUE
J 0
(-2400 3150);
DISPLAY 1.446809 (-2400 3150);
PAINT GREEN (-2400 3150);
DISPLAY INVISIBLE (-2400 3150);
FORCEPROP 1 LAST PATH I66
J 0
(-2727 3275);
DISPLAY 0.872340 (-2727 3275);
PAINT GREEN (-2727 3275);
DISPLAY INVISIBLE (-2727 3275);
FORCEADD TAP..1
(-2875 3525);
FORCEPROP 3 LASTPIN (-2925 3525) SIG_NAME TP_P3E_CPU1_PE1_RSR3_TXP<15>
J 0
(-2915 3535);
DISPLAY 0.659574 (-2915 3535);
PAINT MONO (-2915 3535);
DISPLAY INVISIBLE (-2915 3535);
FORCEPROP 1 LASTPIN (-2925 3525) BN 15
J 0
(-2937 3533);
DISPLAY 0.617021 (-2937 3533);
PAINT GREEN (-2937 3533);
FORCEPROP 2 LAST CDS_LIB mstr_standard
J 2
(-2875 3525);
PAINT MONO (-2875 3525);
DISPLAY INVISIBLE (-2875 3525);
FORCEPROP 1 LAST BODY_TYPE PLUMBING
J 0
(-2875 3575);
DISPLAY 1.446809 (-2875 3575);
PAINT GREEN (-2875 3575);
DISPLAY INVISIBLE (-2875 3575);
FORCEPROP 1 LAST HDL_TAP TRUE
J 0
(-2550 3400);
DISPLAY 1.446809 (-2550 3400);
PAINT GREEN (-2550 3400);
DISPLAY INVISIBLE (-2550 3400);
FORCEPROP 1 LAST PATH I67
J 0
(-2877 3525);
DISPLAY 0.872340 (-2877 3525);
PAINT GREEN (-2877 3525);
DISPLAY INVISIBLE (-2877 3525);
FORCEADD SKX_EXT_B..10
(-4075 2575);
FORCEPROP 1 LAST LOCATION U2D1
J 0
(-4775 3775);
DISPLAY 0.617021 (-4775 3775);
PAINT AQUA (-4775 3775);
FORCEPROP 1 LAST PART_NUMBER TBD
J 0
(-4775 1425);
DISPLAY 0.617021 (-4775 1425);
PAINT BLUE (-4775 1425);
FORCEPROP 1 LAST MATERIAL IC
J 0
(-4775 3725);
DISPLAY 0.617021 (-4775 3725);
PAINT SKYBLUE (-4775 3725);
FORCEPROP 2 LASTPIN (-3325 3525) $PN EC8
J 0
(-3315 3535);
DISPLAY 0.617021 (-3315 3535);
PAINT ORANGE (-3315 3535);
FORCEPROP 2 LASTPIN (-3325 3475) $PN EB7
J 0
(-3315 3485);
DISPLAY 0.617021 (-3315 3485);
PAINT ORANGE (-3315 3485);
FORCEPROP 2 LASTPIN (-3325 3425) $PN DW6
J 0
(-3315 3435);
DISPLAY 0.617021 (-3315 3435);
PAINT ORANGE (-3315 3435);
FORCEPROP 2 LASTPIN (-3325 3375) $PN DT7
J 0
(-3315 3385);
DISPLAY 0.617021 (-3315 3385);
PAINT ORANGE (-3315 3385);
FORCEPROP 2 LASTPIN (-3325 3025) $PN DV5
J 0
(-3315 3035);
DISPLAY 0.617021 (-3315 3035);
PAINT ORANGE (-3315 3035);
FORCEPROP 2 LASTPIN (-3325 2975) $PN DU4
J 0
(-3315 2985);
DISPLAY 0.617021 (-3315 2985);
PAINT ORANGE (-3315 2985);
FORCEPROP 2 LASTPIN (-3325 2925) $PN DU2
J 0
(-3315 2935);
DISPLAY 0.617021 (-3315 2935);
PAINT ORANGE (-3315 2935);
FORCEPROP 2 LASTPIN (-3325 2875) $PN DR4
J 0
(-3315 2885);
DISPLAY 0.617021 (-3315 2885);
PAINT ORANGE (-3315 2885);
FORCEPROP 2 LASTPIN (-3325 2525) $PN DP3
J 0
(-3315 2535);
DISPLAY 0.617021 (-3315 2535);
PAINT ORANGE (-3315 2535);
FORCEPROP 2 LASTPIN (-3325 2475) $PN DL2
J 0
(-3315 2485);
DISPLAY 0.617021 (-3315 2485);
PAINT ORANGE (-3315 2485);
FORCEPROP 2 LASTPIN (-3325 2425) $PN DH3
J 0
(-3315 2435);
DISPLAY 0.617021 (-3315 2435);
PAINT ORANGE (-3315 2435);
FORCEPROP 2 LASTPIN (-3325 2375) $PN DF3
J 0
(-3315 2385);
DISPLAY 0.617021 (-3315 2385);
PAINT ORANGE (-3315 2385);
FORCEPROP 2 LASTPIN (-3325 2025) $PN DC4
J 0
(-3315 2035);
DISPLAY 0.617021 (-3315 2035);
PAINT ORANGE (-3315 2035);
FORCEPROP 2 LASTPIN (-3325 1975) $PN DD3
J 0
(-3315 1985);
DISPLAY 0.617021 (-3315 1985);
PAINT ORANGE (-3315 1985);
FORCEPROP 2 LASTPIN (-3325 1925) $PN DB1
J 0
(-3315 1935);
DISPLAY 0.617021 (-3315 1935);
PAINT ORANGE (-3315 1935);
FORCEPROP 2 LASTPIN (-3325 1875) $PN CW2
J 0
(-3315 1885);
DISPLAY 0.617021 (-3315 1885);
PAINT ORANGE (-3315 1885);
FORCEPROP 2 LASTPIN (-3325 3275) $PN ED9
J 0
(-3315 3285);
DISPLAY 0.617021 (-3315 3285);
PAINT ORANGE (-3315 3285);
FORCEPROP 2 LASTPIN (-3325 3225) $PN EA8
J 0
(-3315 3235);
DISPLAY 0.617021 (-3315 3235);
PAINT ORANGE (-3315 3235);
FORCEPROP 2 LASTPIN (-3325 3175) $PN DY7
J 0
(-3315 3185);
DISPLAY 0.617021 (-3315 3185);
PAINT ORANGE (-3315 3185);
FORCEPROP 2 LASTPIN (-3325 3125) $PN DV7
J 0
(-3315 3135);
DISPLAY 0.617021 (-3315 3135);
PAINT ORANGE (-3315 3135);
FORCEPROP 2 LASTPIN (-3325 2775) $PN DU6
J 0
(-3315 2785);
DISPLAY 0.617021 (-3315 2785);
PAINT ORANGE (-3315 2785);
FORCEPROP 2 LASTPIN (-3325 2725) $PN DW4
J 0
(-3315 2735);
DISPLAY 0.617021 (-3315 2735);
PAINT ORANGE (-3315 2735);
FORCEPROP 2 LASTPIN (-3325 2675) $PN DV3
J 0
(-3315 2685);
DISPLAY 0.617021 (-3315 2685);
PAINT ORANGE (-3315 2685);
FORCEPROP 2 LASTPIN (-3325 2625) $PN DT5
J 0
(-3315 2635);
DISPLAY 0.617021 (-3315 2635);
PAINT ORANGE (-3315 2635);
FORCEPROP 2 LASTPIN (-3325 2275) $PN DN4
J 0
(-3315 2285);
DISPLAY 0.617021 (-3315 2285);
PAINT ORANGE (-3315 2285);
FORCEPROP 2 LASTPIN (-3325 2225) $PN DM3
J 0
(-3315 2235);
DISPLAY 0.617021 (-3315 2235);
PAINT ORANGE (-3315 2235);
FORCEPROP 2 LASTPIN (-3325 2175) $PN DK3
J 0
(-3315 2185);
DISPLAY 0.617021 (-3315 2185);
PAINT ORANGE (-3315 2185);
FORCEPROP 2 LASTPIN (-3325 2125) $PN DG4
J 0
(-3315 2135);
DISPLAY 0.617021 (-3315 2135);
PAINT ORANGE (-3315 2135);
FORCEPROP 2 LASTPIN (-3325 1775) $PN DE4
J 0
(-3315 1785);
DISPLAY 0.617021 (-3315 1785);
PAINT ORANGE (-3315 1785);
FORCEPROP 2 LASTPIN (-3325 1725) $PN DE2
J 0
(-3315 1735);
DISPLAY 0.617021 (-3315 1735);
PAINT ORANGE (-3315 1735);
FORCEPROP 2 LASTPIN (-3325 1675) $PN DC2
J 0
(-3315 1685);
DISPLAY 0.617021 (-3315 1685);
PAINT ORANGE (-3315 1685);
FORCEPROP 2 LASTPIN (-3325 1625) $PN DA2
J 0
(-3315 1635);
DISPLAY 0.617021 (-3315 1635);
PAINT ORANGE (-3315 1635);
FORCEPROP 2 LASTPIN (-4825 3525) $PN DT15
J 2
(-4835 3535);
DISPLAY 0.617021 (-4835 3535);
PAINT ORANGE (-4835 3535);
FORCEPROP 2 LASTPIN (-4825 3475) $PN DV15
J 2
(-4835 3485);
DISPLAY 0.617021 (-4835 3485);
PAINT ORANGE (-4835 3485);
FORCEPROP 2 LASTPIN (-4825 3425) $PN DY13
J 2
(-4835 3435);
DISPLAY 0.617021 (-4835 3435);
PAINT ORANGE (-4835 3435);
FORCEPROP 2 LASTPIN (-4825 3375) $PN DU12
J 2
(-4835 3385);
DISPLAY 0.617021 (-4835 3385);
PAINT ORANGE (-4835 3385);
FORCEPROP 2 LASTPIN (-4825 3025) $PN DP13
J 2
(-4835 3035);
DISPLAY 0.617021 (-4835 3035);
PAINT ORANGE (-4835 3035);
FORCEPROP 2 LASTPIN (-4825 2975) $PN DR12
J 2
(-4835 2985);
DISPLAY 0.617021 (-4835 2985);
PAINT ORANGE (-4835 2985);
FORCEPROP 2 LASTPIN (-4825 2925) $PN DN10
J 2
(-4835 2935);
DISPLAY 0.617021 (-4835 2935);
PAINT ORANGE (-4835 2935);
FORCEPROP 2 LASTPIN (-4825 2875) $PN DK11
J 2
(-4835 2885);
DISPLAY 0.617021 (-4835 2885);
PAINT ORANGE (-4835 2885);
FORCEPROP 2 LASTPIN (-4825 2525) $PN DL10
J 2
(-4835 2535);
DISPLAY 0.617021 (-4835 2535);
PAINT ORANGE (-4835 2535);
FORCEPROP 2 LASTPIN (-4825 2475) $PN DJ8
J 2
(-4835 2485);
DISPLAY 0.617021 (-4835 2485);
PAINT ORANGE (-4835 2485);
FORCEPROP 2 LASTPIN (-4825 2425) $PN DF9
J 2
(-4835 2435);
DISPLAY 0.617021 (-4835 2435);
PAINT ORANGE (-4835 2435);
FORCEPROP 2 LASTPIN (-4825 2375) $PN DD9
J 2
(-4835 2385);
DISPLAY 0.617021 (-4835 2385);
PAINT ORANGE (-4835 2385);
FORCEPROP 2 LASTPIN (-4825 2025) $PN DA10
J 2
(-4835 2035);
DISPLAY 0.617021 (-4835 2035);
PAINT ORANGE (-4835 2035);
FORCEPROP 2 LASTPIN (-4825 1975) $PN DB9
J 2
(-4835 1985);
DISPLAY 0.617021 (-4835 1985);
PAINT ORANGE (-4835 1985);
FORCEPROP 2 LASTPIN (-4825 1925) $PN CY7
J 2
(-4835 1935);
DISPLAY 0.617021 (-4835 1935);
PAINT ORANGE (-4835 1935);
FORCEPROP 2 LASTPIN (-4825 1875) $PN CU8
J 2
(-4835 1885);
DISPLAY 0.617021 (-4835 1885);
PAINT ORANGE (-4835 1885);
FORCEPROP 2 LASTPIN (-4825 3275) $PN DU16
J 2
(-4835 3285);
DISPLAY 0.617021 (-4835 3285);
PAINT ORANGE (-4835 3285);
FORCEPROP 2 LASTPIN (-4825 3225) $PN DY15
J 2
(-4835 3235);
DISPLAY 0.617021 (-4835 3235);
PAINT ORANGE (-4835 3235);
FORCEPROP 2 LASTPIN (-4825 3175) $PN DW14
J 2
(-4835 3185);
DISPLAY 0.617021 (-4835 3185);
PAINT ORANGE (-4835 3185);
FORCEPROP 2 LASTPIN (-4825 3125) $PN DV13
J 2
(-4835 3135);
DISPLAY 0.617021 (-4835 3135);
PAINT ORANGE (-4835 3135);
FORCEPROP 2 LASTPIN (-4825 2775) $PN DT13
J 2
(-4835 2785);
DISPLAY 0.617021 (-4835 2785);
PAINT ORANGE (-4835 2785);
FORCEPROP 2 LASTPIN (-4825 2725) $PN DT11
J 2
(-4835 2735);
DISPLAY 0.617021 (-4835 2735);
PAINT ORANGE (-4835 2735);
FORCEPROP 2 LASTPIN (-4825 2675) $PN DP11
J 2
(-4835 2685);
DISPLAY 0.617021 (-4835 2685);
PAINT ORANGE (-4835 2685);
FORCEPROP 2 LASTPIN (-4825 2625) $PN DM11
J 2
(-4835 2635);
DISPLAY 0.617021 (-4835 2635);
PAINT ORANGE (-4835 2635);
FORCEPROP 2 LASTPIN (-4825 2275) $PN DM9
J 2
(-4835 2285);
DISPLAY 0.617021 (-4835 2285);
PAINT ORANGE (-4835 2285);
FORCEPROP 2 LASTPIN (-4825 2225) $PN DK9
J 2
(-4835 2235);
DISPLAY 0.617021 (-4835 2235);
PAINT ORANGE (-4835 2235);
FORCEPROP 2 LASTPIN (-4825 2175) $PN DH9
J 2
(-4835 2185);
DISPLAY 0.617021 (-4835 2185);
PAINT ORANGE (-4835 2185);
FORCEPROP 2 LASTPIN (-4825 2125) $PN DE10
J 2
(-4835 2135);
DISPLAY 0.617021 (-4835 2135);
PAINT ORANGE (-4835 2135);
FORCEPROP 2 LASTPIN (-4825 1775) $PN DC10
J 2
(-4835 1785);
DISPLAY 0.617021 (-4835 1785);
PAINT ORANGE (-4835 1785);
FORCEPROP 2 LASTPIN (-4825 1725) $PN DC8
J 2
(-4835 1735);
DISPLAY 0.617021 (-4835 1735);
PAINT ORANGE (-4835 1735);
FORCEPROP 2 LASTPIN (-4825 1675) $PN DA8
J 2
(-4835 1685);
DISPLAY 0.617021 (-4835 1685);
PAINT ORANGE (-4835 1685);
FORCEPROP 2 LASTPIN (-4825 1625) $PN CW8
J 2
(-4835 1635);
DISPLAY 0.617021 (-4835 1635);
PAINT ORANGE (-4835 1635);
FORCEPROP 1 LAST PACK_TYPE BGA1
J 0
(-4775 3825);
PAINT SKYBLUE (-4775 3825);
DISPLAY INVISIBLE (-4775 3825);
FORCEPROP 2 LAST SEC_TYPE BGA1
J 0
(-4775 3825);
DISPLAY 1.021277 (-4775 3825);
PAINT ORANGE (-4775 3825);
DISPLAY INVISIBLE (-4775 3825);
FORCEPROP 2 LAST CDS_LIB chpset_lib
J 0
(-4075 2575);
PAINT ORANGE (-4075 2575);
DISPLAY INVISIBLE (-4075 2575);
FORCEPROP 2 LAST SEC 10
J 0
(-4775 3825);
DISPLAY 0.680851 (-4775 3825);
PAINT MONO (-4775 3825);
DISPLAY INVISIBLE (-4775 3825);
FORCEPROP 2 LAST CDS_LOCATION U2D1
J 0
(-4775 3775);
DISPLAY 0.617021 (-4775 3775);
PAINT AQUA (-4775 3775);
DISPLAY INVISIBLE (-4775 3775);
FORCEPROP 1 LAST PATH I68
J 0
(-4075 3725);
PAINT GREEN (-4075 3725);
DISPLAY INVISIBLE (-4075 3725);
FORCEADD TAP..1
R 2
(-5350 1875);
FORCEPROP 3 LASTPIN (-5300 1875) SIG_NAME TP_P3E_CPU1_PE1_MP_RXP<0>
J 0
(-5290 1885);
DISPLAY 0.659574 (-5290 1885);
PAINT MONO (-5290 1885);
DISPLAY INVISIBLE (-5290 1885);
FORCEPROP 1 LASTPIN (-5300 1875) BN 0
J 2
(-5288 1883);
DISPLAY 0.617021 (-5288 1883);
PAINT GREEN (-5288 1883);
FORCEPROP 2 LAST CDS_LIB mstr_standard
J 0
(-5350 1875);
PAINT MONO (-5350 1875);
DISPLAY INVISIBLE (-5350 1875);
FORCEPROP 1 LAST BODY_TYPE PLUMBING
J 2
(-5350 1925);
DISPLAY 1.446809 (-5350 1925);
PAINT GREEN (-5350 1925);
DISPLAY INVISIBLE (-5350 1925);
FORCEPROP 1 LAST HDL_TAP TRUE
J 2
(-5675 1750);
DISPLAY 1.446809 (-5675 1750);
PAINT GREEN (-5675 1750);
DISPLAY INVISIBLE (-5675 1750);
FORCEPROP 1 LAST PATH I7
J 2
(-5348 1875);
DISPLAY 0.872340 (-5348 1875);
PAINT GREEN (-5348 1875);
DISPLAY INVISIBLE (-5348 1875);
FORCEADD TAP..1
R 2
(-5350 1925);
FORCEPROP 3 LASTPIN (-5300 1925) SIG_NAME TP_P3E_CPU1_PE1_MP_RXP<1>
J 0
(-5290 1935);
DISPLAY 0.659574 (-5290 1935);
PAINT MONO (-5290 1935);
DISPLAY INVISIBLE (-5290 1935);
FORCEPROP 1 LASTPIN (-5300 1925) BN 1
J 2
(-5288 1933);
DISPLAY 0.617021 (-5288 1933);
PAINT GREEN (-5288 1933);
FORCEPROP 2 LAST CDS_LIB mstr_standard
J 0
(-5350 1925);
PAINT MONO (-5350 1925);
DISPLAY INVISIBLE (-5350 1925);
FORCEPROP 1 LAST BODY_TYPE PLUMBING
J 2
(-5350 1975);
DISPLAY 1.446809 (-5350 1975);
PAINT GREEN (-5350 1975);
DISPLAY INVISIBLE (-5350 1975);
FORCEPROP 1 LAST HDL_TAP TRUE
J 2
(-5675 1800);
DISPLAY 1.446809 (-5675 1800);
PAINT GREEN (-5675 1800);
DISPLAY INVISIBLE (-5675 1800);
FORCEPROP 1 LAST PATH I8
J 2
(-5348 1925);
DISPLAY 0.872340 (-5348 1925);
PAINT GREEN (-5348 1925);
DISPLAY INVISIBLE (-5348 1925);
FORCEADD PRELIM..10
(-4065 2565);
PAINT GRAY (-4065 2565);
FORCEPROP 2 LAST CDS_LIB mstr_misc
J 0
(-4065 2565);
PAINT ORANGE (-4065 2565);
DISPLAY INVISIBLE (-4065 2565);
FORCEPROP 1 LAST COMMENT_BODY TRUE
J 0
(-4065 2565);
PAINT ORANGE (-4065 2565);
DISPLAY INVISIBLE (-4065 2565);
FORCEADD DESIGN_NOTE..1
(-4550 1300);
FORCEPROP 0 LAST L1 CPU SYMBOLS 1-30 ARE PRELIMINARY AND SUBJECT TO CHANGE
J 0
(-4750 1175);
DISPLAY 1.021277 (-4750 1175);
PAINT ORANGE (-4750 1175);
FORCEPROP 2 LAST CDS_LIB mstr_symbols
J 0
(-4550 1300);
PAINT ORANGE (-4550 1300);
DISPLAY INVISIBLE (-4550 1300);
FORCEPROP 1 LAST COMMENT_BODY TRUE
J 0
(-4525 1400);
DISPLAY 0.978723 (-4525 1400);
PAINT ORANGE (-4525 1400);
DISPLAY INVISIBLE (-4525 1400);
FORCEADD INTEL_CORP_BPAGE..1
(0 0);
FORCEPROP 1 LAST CDS_CON_LAST_MODIFIED Tue Dec 01 11:51:36 2015
J 0
(-1425 325);
DISPLAY 1.340426 (-1425 325);
PAINT GREEN (-1425 325);
DISPLAY INVISIBLE (-1425 325);
FORCEPROP 1 LAST CUSTOM_TXT_CDS <CURRENT_DESIGN_SHEET> OF <TOTAL_DESIGN_SHEETS>
J 0
(-500 25);
PAINT GREEN (-500 25);
FORCEPROP 1 LAST CUSTOM_TXT_CDS <CON_LAST_MODIFIED>
J 0
(-1925 350);
PAINT GREEN (-1925 350);
FORCEPROP 2 LAST CUSTOM_TXT_CDS <XR_PAGE_TITLE>
J 0
(-7890 5250);
DISPLAY 0.638298 (-7890 5250);
PAINT PINK (-7890 5250);
DISPLAY INVISIBLE (-7890 5250);
FORCEPROP 1 LAST SCH_ADDRESS3 Santa Clara, CA 95052-8119
J 0
(-3975 25);
DISPLAY 0.617021 (-3975 25);
PAINT GREEN (-3975 25);
FORCEPROP 1 LAST SCH_ADDRESS2 P.O. BOX 58119
J 0
(-3975 75);
DISPLAY 0.617021 (-3975 75);
PAINT GREEN (-3975 75);
FORCEPROP 1 LAST SCH_ADDRESS1 2200 Mission College Blvd.
J 0
(-3975 125);
DISPLAY 0.617021 (-3975 125);
PAINT GREEN (-3975 125);
FORCEPROP 1 LAST SCH_TITLE SKYLAKE - SKT1 - 10 OF 21
J 0
(-7950 50);
DISPLAY 1.212766 (-7950 50);
PAINT GREEN (-7950 50);
FORCEPROP 1 LAST SCH_NUMBER H4694802
J 0
(-1300 150);
DISPLAY 1.212766 (-1300 150);
PAINT YELLOW (-1300 150);
FORCEPROP 1 LAST SCH_DEPT BESD
J 1
(-4450 100);
DISPLAY 1.212766 (-4450 100);
PAINT YELLOW (-4450 100);
FORCEPROP 1 LAST SCH_REV 2.420
J 0
(-250 150);
DISPLAY 0.978723 (-250 150);
PAINT YELLOW (-250 150);
FORCEPROP 2 LAST CDS_LIB mstr_symbols
J 0
(0 0);
PAINT ORANGE (0 0);
DISPLAY INVISIBLE (0 0);
FORCEPROP 2 LAST PAGE_BORDER TRUE
J 0
(-7890 5250);
DISPLAY 0.851064 (-7890 5250);
PAINT PINK (-7890 5250);
DISPLAY INVISIBLE (-7890 5250);
FORCEPROP 1 LAST COMMENT_BODY TRUE
J 0
(12 12);
DISPLAY 0.638298 (12 12);
PAINT GREEN (12 12);
DISPLAY INVISIBLE (12 12);
FORCEPROP 2 LAST CDS_XR_PAGE_TITLE CR-64 : @BASEBOARD_FAB2_LIB.BASEBOARD_FAB2(SCH_1):PAGE64
J 0
(-7890 5250);
DISPLAY 0.638298 (-7890 5250);
PAINT PINK (-7890 5250);
DISPLAY INVISIBLE (-7890 5250);
WIRE 17 -1 (-2675 3300)(-2675 3500);
WIRE 17 -1 (-2675 3250)(-2675 3300);
WIRE 17 -1 (-2675 3500)(-1500 3500);
FORCEPROP 2 LAST SIG_NAME TP_P3E_CPU1_PE1_RSR3_TXN<15:8>
J 0
(-2635 3510);
DISPLAY 0.617021 (-2635 3510);
PAINT ORANGE (-2635 3510);
FORCEPROP 2 LASTPROP $XRERR UNIQUE?
J 0
(-1470 3500);
DISPLAY 0.638298 (-1470 3500);
PAINT MONO (-1470 3500);
DISPLAY INVISIBLE (-1470 3500);
WIRE 17 -1 (-2675 3200)(-2675 3250);
WIRE 17 -1 (-2675 3150)(-2675 3200);
WIRE 17 -1 (-2675 2800)(-2675 3150);
WIRE 17 -1 (-2675 2750)(-2675 2800);
WIRE 17 -1 (-2675 2700)(-2675 2750);
WIRE 17 -1 (-2675 2650)(-2675 2700);
WIRE 17 -1 (-2675 2250)(-2675 2300);
WIRE 17 -1 (-2675 2200)(-2675 2250);
WIRE 17 -1 (-2675 2150)(-2675 2200);
WIRE 17 -1 (-2675 1800)(-2675 2150);
WIRE 17 -1 (-2675 1750)(-2675 1800);
WIRE 17 -1 (-2675 1700)(-2675 1750);
WIRE 17 -1 (-2675 1650)(-2675 1700);
WIRE 17 -1 (-2675 1650)(-2675 1575);
WIRE 17 -1 (-2675 1575)(-1700 1575);
FORCEPROP 0 LAST SIG_NAME TP_P3E_CPU1_PE1_MP_TXN<7:0>
J 0
(-2385 1585);
DISPLAY 0.617021 (-2385 1585);
PAINT ORANGE (-2385 1585);
FORCEPROP 2 LASTPROP $XRERR UNIQUE?
J 0
(-1572 1585);
DISPLAY 0.638298 (-1572 1585);
PAINT MONO (-1572 1585);
DISPLAY INVISIBLE (-1572 1585);
WIRE 17 -1 (-2825 3550)(-2825 3625);
WIRE 17 -1 (-2825 3500)(-2825 3550);
WIRE 17 -1 (-2825 3625)(-1500 3625);
FORCEPROP 2 LAST SIG_NAME TP_P3E_CPU1_PE1_RSR3_TXP<15:8>
J 0
(-2635 3635);
DISPLAY 0.617021 (-2635 3635);
PAINT ORANGE (-2635 3635);
FORCEPROP 2 LASTPROP $XRERR UNIQUE?
J 0
(-1470 3625);
DISPLAY 0.638298 (-1470 3625);
PAINT MONO (-1470 3625);
DISPLAY INVISIBLE (-1470 3625);
WIRE 17 -1 (-2825 3450)(-2825 3500);
WIRE 17 -1 (-2825 3450)(-2825 3400);
WIRE 17 -1 (-2825 3050)(-2825 3400);
WIRE 17 -1 (-2825 3000)(-2825 3050);
WIRE 17 -1 (-2825 2950)(-2825 3000);
WIRE 17 -1 (-2825 2900)(-2825 2950);
WIRE 17 -1 (-2825 2500)(-2825 2550);
WIRE 17 -1 (-2825 2450)(-2825 2500);
WIRE 17 -1 (-2825 2400)(-2825 2450);
WIRE 17 -1 (-2825 2050)(-2825 2400);
WIRE 17 -1 (-2825 2000)(-2825 2050);
WIRE 17 -1 (-2825 1950)(-2825 2000);
WIRE 17 -1 (-2825 1950)(-2825 1900);
WIRE 17 -1 (-2825 1900)(-2825 1425);
WIRE 17 -1 (-2825 1425)(-1700 1425);
FORCEPROP 0 LAST SIG_NAME TP_P3E_CPU1_PE1_MP_TXP<7:0>
J 0
(-2385 1435);
DISPLAY 0.617021 (-2385 1435);
PAINT ORANGE (-2385 1435);
FORCEPROP 2 LASTPROP $XRERR UNIQUE?
J 0
(-1572 1435);
DISPLAY 0.638298 (-1572 1435);
PAINT MONO (-1572 1435);
DISPLAY INVISIBLE (-1572 1435);
WIRE 17 -1 (-5550 3500)(-5550 3300);
WIRE 17 -1 (-6700 3500)(-5550 3500);
FORCEPROP 2 LAST SIG_NAME TP_P3E_CPU1_PE1_RSR3_RXN<15:8>
J 0
(-6660 3510);
DISPLAY 0.617021 (-6660 3510);
PAINT ORANGE (-6660 3510);
FORCEPROP 2 LASTPROP $XRERR UNIQUE?
J 0
(-6940 3500);
DISPLAY 0.638298 (-6940 3500);
PAINT MONO (-6940 3500);
DISPLAY INVISIBLE (-6940 3500);
WIRE 17 -1 (-5550 3250)(-5550 3300);
WIRE 17 -1 (-5550 3250)(-5550 3200);
WIRE 17 -1 (-5550 3200)(-5550 3150);
WIRE 17 -1 (-5550 3150)(-5550 2800);
WIRE 17 -1 (-5550 2800)(-5550 2750);
WIRE 17 -1 (-5550 2750)(-5550 2700);
WIRE 17 -1 (-5550 2700)(-5550 2650);
WIRE 17 -1 (-5550 2300)(-5550 2250);
WIRE 17 -1 (-5550 2250)(-5550 2200);
WIRE 17 -1 (-5550 2200)(-5550 2150);
WIRE 17 -1 (-5550 2150)(-5550 1800);
WIRE 17 -1 (-5550 1800)(-5550 1750);
WIRE 17 -1 (-5550 1750)(-5550 1700);
WIRE 17 -1 (-5550 1700)(-5550 1650);
WIRE 17 -1 (-5550 1650)(-5550 1575);
WIRE 17 -1 (-5550 1575)(-6750 1575);
FORCEPROP 0 LAST SIG_NAME TP_P3E_CPU1_PE1_MP_RXN<7:0>
J 0
(-6735 1585);
DISPLAY 0.617021 (-6735 1585);
PAINT ORANGE (-6735 1585);
FORCEPROP 2 LASTPROP $XRERR UNIQUE?
J 0
(-6990 1575);
DISPLAY 0.638298 (-6990 1575);
PAINT MONO (-6990 1575);
DISPLAY INVISIBLE (-6990 1575);
WIRE 17 -1 (-5400 3625)(-5400 3550);
WIRE 17 -1 (-6700 3625)(-5400 3625);
FORCEPROP 2 LAST SIG_NAME TP_P3E_CPU1_PE1_RSR3_RXP<15:8>
J 0
(-6660 3635);
DISPLAY 0.617021 (-6660 3635);
PAINT ORANGE (-6660 3635);
FORCEPROP 2 LASTPROP $XRERR UNIQUE?
J 0
(-6940 3625);
DISPLAY 0.638298 (-6940 3625);
PAINT MONO (-6940 3625);
DISPLAY INVISIBLE (-6940 3625);
WIRE 17 -1 (-5400 3550)(-5400 3500);
WIRE 17 -1 (-5400 3500)(-5400 3450);
WIRE 17 -1 (-5400 3450)(-5400 3400);
WIRE 17 -1 (-5400 3400)(-5400 3050);
WIRE 17 -1 (-5400 3050)(-5400 3000);
WIRE 17 -1 (-5400 3000)(-5400 2950);
WIRE 17 -1 (-5400 2950)(-5400 2900);
WIRE 17 -1 (-5400 2550)(-5400 2500);
WIRE 17 -1 (-5400 2500)(-5400 2450);
WIRE 17 -1 (-5400 2450)(-5400 2400);
WIRE 17 -1 (-5400 2400)(-5400 2050);
WIRE 17 -1 (-5400 2050)(-5400 2000);
WIRE 17 -1 (-5400 2000)(-5400 1950);
WIRE 17 -1 (-5400 1950)(-5400 1900);
WIRE 17 -1 (-5400 1900)(-5400 1450);
WIRE 17 -1 (-5400 1450)(-6750 1450);
FORCEPROP 0 LAST SIG_NAME TP_P3E_CPU1_PE1_MP_RXP<7:0>
J 0
(-6735 1460);
DISPLAY 0.617021 (-6735 1460);
PAINT ORANGE (-6735 1460);
FORCEPROP 2 LASTPROP $XRERR UNIQUE?
J 0
(-6990 1450);
DISPLAY 0.638298 (-6990 1450);
PAINT MONO (-6990 1450);
DISPLAY INVISIBLE (-6990 1450);
WIRE 16 -1 (-5300 1875)(-4825 1875);
WIRE 16 -1 (-5300 1925)(-4825 1925);
WIRE 16 -1 (-5300 1975)(-4825 1975);
WIRE 16 -1 (-5300 2025)(-4825 2025);
WIRE 16 -1 (-5450 1625)(-4825 1625);
WIRE 16 -1 (-5450 1675)(-4825 1675);
WIRE 16 -1 (-5450 1725)(-4825 1725);
WIRE 16 -1 (-5450 1775)(-4825 1775);
WIRE 16 -1 (-5300 2375)(-4825 2375);
WIRE 16 -1 (-5300 2425)(-4825 2425);
WIRE 16 -1 (-5300 2475)(-4825 2475);
WIRE 16 -1 (-5300 2525)(-4825 2525);
WIRE 16 -1 (-5300 2875)(-4825 2875);
WIRE 16 -1 (-5300 2925)(-4825 2925);
WIRE 16 -1 (-5300 2975)(-4825 2975);
WIRE 16 -1 (-5300 3025)(-4825 3025);
WIRE 16 -1 (-5300 3375)(-4825 3375);
WIRE 16 -1 (-4825 3425)(-5300 3425);
WIRE 16 -1 (-5300 3475)(-4825 3475);
WIRE 16 -1 (-5300 3525)(-4825 3525);
WIRE 16 -1 (-5450 2125)(-4825 2125);
WIRE 16 -1 (-5450 2175)(-4825 2175);
WIRE 16 -1 (-4825 2225)(-5450 2225);
WIRE 16 -1 (-5450 2275)(-4825 2275);
WIRE 16 -1 (-5450 2625)(-4825 2625);
WIRE 16 -1 (-5450 2675)(-4825 2675);
WIRE 16 -1 (-5450 2725)(-4825 2725);
WIRE 16 -1 (-5450 2775)(-4825 2775);
WIRE 16 -1 (-5450 3125)(-4825 3125);
WIRE 16 -1 (-5450 3175)(-4825 3175);
WIRE 16 -1 (-5450 3225)(-4825 3225);
WIRE 16 -1 (-5450 3275)(-4825 3275);
WIRE 16 -1 (-3325 1875)(-2925 1875);
WIRE 16 -1 (-2925 1925)(-3325 1925);
WIRE 16 -1 (-3325 1975)(-2925 1975);
WIRE 16 -1 (-2925 2025)(-3325 2025);
WIRE 16 -1 (-2775 1625)(-3325 1625);
WIRE 16 -1 (-2775 1675)(-3325 1675);
WIRE 16 -1 (-2775 1725)(-3325 1725);
WIRE 16 -1 (-2775 1775)(-3325 1775);
WIRE 16 -1 (-2925 2375)(-3325 2375);
WIRE 16 -1 (-2925 2425)(-3325 2425);
WIRE 16 -1 (-2925 2475)(-3325 2475);
WIRE 16 -1 (-2925 2525)(-3325 2525);
WIRE 16 -1 (-2925 2875)(-3325 2875);
WIRE 16 -1 (-2925 2925)(-3325 2925);
WIRE 16 -1 (-2925 2975)(-3325 2975);
WIRE 16 -1 (-2925 3025)(-3325 3025);
WIRE 16 -1 (-2925 3375)(-3325 3375);
WIRE 16 -1 (-3325 3425)(-2925 3425);
WIRE 16 -1 (-3325 3475)(-2925 3475);
WIRE 16 -1 (-2925 3525)(-3325 3525);
WIRE 16 -1 (-2775 2125)(-3325 2125);
WIRE 16 -1 (-2775 2175)(-3325 2175);
WIRE 16 -1 (-3325 2225)(-2775 2225);
WIRE 16 -1 (-3325 2275)(-2775 2275);
WIRE 16 -1 (-2775 2625)(-3325 2625);
WIRE 16 -1 (-3325 2675)(-2775 2675);
WIRE 16 -1 (-2775 2725)(-3325 2725);
WIRE 16 -1 (-2775 2775)(-3325 2775);
WIRE 16 -1 (-3325 3125)(-2775 3125);
WIRE 16 -1 (-2775 3175)(-3325 3175);
WIRE 16 -1 (-2775 3225)(-3325 3225);
WIRE 16 -1 (-2775 3275)(-3325 3275);
FORCENOTE
ROOM=CPU1
(-7900 350) 0;
DISPLAY LEFT (-7900 350);
DISPLAY 1.723404 (-7900 350);
PAINT PURPLE (-7900 350);
FORCENOTE
BOM_COST=PROC_SOCKET
(-7900 225) 0;
DISPLAY LEFT (-7900 225);
DISPLAY 1.723404 (-7900 225);
PAINT PURPLE (-7900 225);
QUIT
